FILE_TYPE = MACRO_DRAWING;
SET COLOR_WIRE YELLOW;
SET COLOR_PROP ORANGE;
SET COLOR_DOT WHITE;
SET COLOR_ARC YELLOW;
SET COLOR_BODY GREEN;
SET COLOR_NOTE PURPLE;
SET PROP_DISPLAY VALUE;
SET PAGE_NUMBER P350;
FORCEADD OFFPAGE..1
(-3025 13175);
FORCEPROP 2 LAST $XR1 82 
J 0
(-3367 13175);
DISPLAY 0.638298 (-3367 13175);
PAINT MONO (-3367 13175);
FORCEPROP 2 LAST $XR0 150 
J 0
(-3277 13175);
DISPLAY 0.638298 (-3277 13175);
PAINT MONO (-3277 13175);
FORCEPROP 2 LAST CDS_LIB standard
J 0
(-3025 13175);
DISPLAY INVISIBLE (-3025 13175);
FORCEPROP 1 LAST OFFPAGE TRUE
J 0
(-2700 13050);
DISPLAY 0.872340 (-2700 13050);
PAINT GREEN (-2700 13050);
DISPLAY INVISIBLE (-2700 13050);
FORCEPROP 1 LAST COMMENT_BODY TRUE
J 0
(-2900 13075);
DISPLAY 0.872340 (-2900 13075);
PAINT PEACH (-2900 13075);
DISPLAY INVISIBLE (-2900 13075);
FORCEPROP 2 LAST PATH I1
J 0
(-3300 13225);
DISPLAY 0.680851 (-3300 13225);
DISPLAY INVISIBLE (-3300 13225);
FORCEADD UNIVERSAL_GND..1
(-750 12850);
FORCEPROP 3 LASTPIN (-750 12900) SIG_NAME GND\g
J 0
(-740 12910);
DISPLAY 0.659574 (-740 12910);
PAINT MONO (-740 12910);
DISPLAY INVISIBLE (-740 12910);
FORCEPROP 2 LAST CDS_LIB pure_quanta_power
J 0
(-750 12850);
DISPLAY INVISIBLE (-750 12850);
FORCEPROP 1 LAST HDL_POWER GND
J 1
(-725 12775);
DISPLAY 0.872340 (-725 12775);
PAINT GREEN (-725 12775);
DISPLAY INVISIBLE (-725 12775);
FORCEPROP 1 LAST PATH I10
J 0
(-675 12850);
DISPLAY 0.872340 (-675 12850);
PAINT AQUA (-675 12850);
DISPLAY INVISIBLE (-675 12850);
FORCEADD Q_RES..2
(-75 11575);
FORCEPROP 1 LAST LOCATION PR3999
J 0
(-25 11625);
DISPLAY 0.638298 (-25 11625);
FORCEPROP 0 LAST $SEC 1
J 0
(-25 11725);
DISPLAY 0.680851 (-25 11725);
PAINT MONO (-25 11725);
DISPLAY INVISIBLE (-25 11725);
FORCEPROP 0 LAST CDS_SEC 1
J 0
(-25 11700);
DISPLAY INVISIBLE (-25 11700);
FORCEPROP 1 LASTPIN (-75 11675) $PN 1
J 0
(-70 11637);
DISPLAY 0.787234 (-70 11637);
PAINT MONO (-70 11637);
FORCEPROP 1 LASTPIN (-75 11475) $PN 2
J 0
(-70 11485);
DISPLAY 0.787234 (-70 11485);
PAINT MONO (-70 11485);
FORCEPROP 1 LAST VALUE 24.3K
J 0
(-25 11600);
DISPLAY 0.510638 (-25 11600);
FORCEPROP 1 LAST TOLERANCE 1%
J 0
(-25 11575);
DISPLAY 0.510638 (-25 11575);
FORCEPROP 0 LAST ROOM SCM_P12V_MPS_BOM2
J 0
(-25 11675);
DISPLAY 0.446809 (-25 11675);
PAINT RED (-25 11675);
FORCEPROP 1 LAST WATTAGE 1/16W
J 0
(-25 11550);
DISPLAY 0.510638 (-25 11550);
FORCEPROP 1 LAST MATERIAL CHIP
J 0
(-25 11525);
DISPLAY 0.510638 (-25 11525);
PAINT RED (-25 11525);
FORCEPROP 1 LAST PACK_TYPE 0402LF
J 0
(-25 11475);
DISPLAY 0.510638 (-25 11475);
FORCEPROP 2 LAST CDS_LIB pure_quanta
J 0
(-75 11575);
DISPLAY INVISIBLE (-75 11575);
FORCEPROP 1 LAST PATH I11
J 0
(-25 11750);
DISPLAY 0.978723 (-25 11750);
PAINT WHITE (-25 11750);
DISPLAY INVISIBLE (-25 11750);
FORCEPROP 1 LAST PART_NUMBER CS32432FB03
J 0
(-25 11500);
DISPLAY 0.510638 (-25 11500);
DISPLAY INVISIBLE (-25 11500);
FORCEADD Q_RES..2
(350 11550);
FORCEPROP 1 LAST LOCATION PR4540
J 0
(400 11600);
DISPLAY 0.638298 (400 11600);
FORCEPROP 0 LAST $SEC 1
J 0
(400 11650);
DISPLAY 0.680851 (400 11650);
PAINT MONO (400 11650);
DISPLAY INVISIBLE (400 11650);
FORCEPROP 0 LAST CDS_SEC 1
J 0
(400 11650);
DISPLAY 1.021277 (400 11650);
DISPLAY INVISIBLE (400 11650);
FORCEPROP 1 LASTPIN (350 11650) $PN 1
J 0
(355 11612);
DISPLAY 0.787234 (355 11612);
PAINT MONO (355 11612);
FORCEPROP 1 LASTPIN (350 11450) $PN 2
J 0
(355 11460);
DISPLAY 0.787234 (355 11460);
PAINT MONO (355 11460);
FORCEPROP 1 LAST WATTAGE 1/16W
J 0
(400 11525);
DISPLAY 0.510638 (400 11525);
FORCEPROP 1 LAST MATERIAL CHIP
J 0
(400 11500);
DISPLAY 0.510638 (400 11500);
PAINT RED (400 11500);
FORCEPROP 0 LAST ROOM SCM_P12V_MPS_BOM2
J 0
(400 11650);
DISPLAY 0.361702 (400 11650);
PAINT RED (400 11650);
FORCEPROP 1 LAST VALUE 20K
J 0
(400 11575);
DISPLAY 0.510638 (400 11575);
FORCEPROP 1 LAST TOLERANCE 1%
J 0
(400 11550);
DISPLAY 0.510638 (400 11550);
FORCEPROP 1 LAST PACK_TYPE 0402LF
J 0
(400 11450);
DISPLAY 0.510638 (400 11450);
FORCEPROP 2 LAST CDS_LIB pure_quanta
J 0
(350 11550);
DISPLAY INVISIBLE (350 11550);
FORCEPROP 1 LAST PATH I12
J 0
(400 11725);
DISPLAY 0.978723 (400 11725);
PAINT WHITE (400 11725);
DISPLAY INVISIBLE (400 11725);
FORCEPROP 1 LAST PART_NUMBER CS32002FB06
J 0
(400 11475);
DISPLAY 0.510638 (400 11475);
DISPLAY INVISIBLE (400 11475);
FORCEADD GND..1
(425 11900);
FORCEPROP 3 LASTPIN (425 11950) SIG_NAME GND\g
J 0
(435 11960);
DISPLAY 0.659574 (435 11960);
PAINT MONO (435 11960);
DISPLAY INVISIBLE (435 11960);
FORCEPROP 2 LAST CDS_LIB pure_quanta_power
J 0
(425 11900);
DISPLAY INVISIBLE (425 11900);
FORCEPROP 1 LAST SIZE 1B
J 0
(500 11850);
DISPLAY 0.872340 (500 11850);
PAINT GREEN (500 11850);
DISPLAY INVISIBLE (500 11850);
FORCEPROP 1 LAST HDL_POWER GND
J 0
(425 12050);
DISPLAY 0.872340 (425 12050);
PAINT GREEN (425 12050);
DISPLAY INVISIBLE (425 12050);
FORCEPROP 1 LAST PATH I13
J 0
(500 11900);
DISPLAY 0.872340 (500 11900);
PAINT AQUA (500 11900);
DISPLAY INVISIBLE (500 11900);
FORCEADD Q_RES..1
(300 12150);
FORCEPROP 1 LAST LOCATION R3998
J 0
(250 12200);
DISPLAY 0.787234 (250 12200);
FORCEPROP 0 LAST $SEC 1
J 0
(250 12250);
DISPLAY 0.680851 (250 12250);
PAINT MONO (250 12250);
DISPLAY INVISIBLE (250 12250);
FORCEPROP 0 LAST CDS_SEC 1
J 0
(250 12250);
DISPLAY 1.021277 (250 12250);
DISPLAY INVISIBLE (250 12250);
FORCEPROP 1 LASTPIN (200 12150) $PN 1
J 0
(212 12162);
DISPLAY 0.787234 (212 12162);
PAINT MONO (212 12162);
FORCEPROP 1 LASTPIN (400 12150) $PN 2
J 0
(362 12162);
DISPLAY 0.787234 (362 12162);
PAINT MONO (362 12162);
FORCEPROP 1 LAST PACK_TYPE 0402LF
J 0
(550 12150);
DISPLAY 0.510638 (550 12150);
FORCEPROP 1 LAST TOLERANCE 5%
J 0
(475 12150);
DISPLAY 0.510638 (475 12150);
FORCEPROP 1 LAST VALUE 0
J 2
(450 12150);
DISPLAY 0.510638 (450 12150);
FORCEPROP 1 LAST WATTAGE 1/16W
J 2
(500 12075);
DISPLAY 0.510638 (500 12075);
FORCEPROP 0 LAST ROOM SCM_P12V_MPS_BOM2
J 0
(250 12250);
DISPLAY 0.553191 (250 12250);
PAINT RED (250 12250);
FORCEPROP 1 LAST MATERIAL CHIP
J 0
(225 12075);
DISPLAY 0.510638 (225 12075);
PAINT RED (225 12075);
FORCEPROP 2 LAST CDS_LIB pure_quanta
J 0
(300 12150);
DISPLAY INVISIBLE (300 12150);
FORCEPROP 1 LAST PATH I14
J 0
(250 12300);
DISPLAY 0.978723 (250 12300);
PAINT WHITE (250 12300);
DISPLAY INVISIBLE (250 12300);
FORCEPROP 1 LAST PART_NUMBER CS00002JB13
J 0
(225 12100);
DISPLAY 0.510638 (225 12100);
DISPLAY INVISIBLE (225 12100);
FORCEADD OFFPAGE..1
(-3750 14275);
PAINT AQUA (-3750 14275);
FORCEPROP 2 LAST $XR0 80 
J 0
(-4001 14275);
DISPLAY 0.638298 (-4001 14275);
PAINT MONO (-4001 14275);
FORCEPROP 2 LAST CDS_LIB standard
J 0
(-3750 14275);
DISPLAY INVISIBLE (-3750 14275);
FORCEPROP 1 LAST OFFPAGE TRUE
J 0
(-3425 14150);
DISPLAY 0.872340 (-3425 14150);
PAINT AQUA (-3425 14150);
DISPLAY INVISIBLE (-3425 14150);
FORCEPROP 1 LAST COMMENT_BODY TRUE
J 0
(-3625 14175);
DISPLAY 0.872340 (-3625 14175);
PAINT GREEN (-3625 14175);
DISPLAY INVISIBLE (-3625 14175);
FORCEPROP 2 LAST PATH I15
J 0
(-4000 14325);
DISPLAY 0.680851 (-4000 14325);
DISPLAY INVISIBLE (-4000 14325);
FORCEADD UNIVERSAL_POWER..1
(-2750 13625);
FORCEPROP 3 LASTPIN (-2750 13575) SIG_NAME P3V3_AUX\g
J 0
(-2740 13585);
DISPLAY 0.659574 (-2740 13585);
PAINT MONO (-2740 13585);
DISPLAY INVISIBLE (-2740 13585);
FORCEPROP 1 LAST HDL_POWER P3V3_AUX
J 1
(-2750 13675);
DISPLAY 0.702128 (-2750 13675);
PAINT GREEN (-2750 13675);
FORCEPROP 2 LAST CDS_LIB pure_quanta_power
J 0
(-2750 13625);
DISPLAY INVISIBLE (-2750 13625);
FORCEPROP 1 LAST PATH I16
J 0
(-2700 13650);
DISPLAY 0.872340 (-2700 13650);
PAINT AQUA (-2700 13650);
DISPLAY INVISIBLE (-2700 13650);
FORCEADD Q_RES..1
(-2825 14275);
FORCEPROP 1 LAST LOCATION R3996
J 0
(-2875 14350);
DISPLAY 0.978723 (-2875 14350);
FORCEPROP 0 LAST $SEC 1
J 0
(-2875 14375);
DISPLAY 0.680851 (-2875 14375);
PAINT MONO (-2875 14375);
DISPLAY INVISIBLE (-2875 14375);
FORCEPROP 0 LAST CDS_SEC 1
J 0
(-2875 14375);
DISPLAY 1.021277 (-2875 14375);
DISPLAY INVISIBLE (-2875 14375);
FORCEPROP 1 LASTPIN (-2925 14275) $PN 1
J 0
(-2913 14287);
DISPLAY 0.787234 (-2913 14287);
PAINT MONO (-2913 14287);
FORCEPROP 1 LASTPIN (-2725 14275) $PN 2
J 0
(-2763 14287);
DISPLAY 0.787234 (-2763 14287);
PAINT MONO (-2763 14287);
FORCEPROP 1 LAST VALUE 0
J 2
(-2625 14275);
DISPLAY 0.638298 (-2625 14275);
FORCEPROP 1 LAST TOLERANCE 5%
J 0
(-2600 14275);
DISPLAY 0.638298 (-2600 14275);
FORCEPROP 1 LAST WATTAGE 1/16W
J 2
(-2600 14125);
DISPLAY 0.638298 (-2600 14125);
FORCEPROP 1 LAST MATERIAL CHIP
J 0
(-2975 14125);
DISPLAY 0.638298 (-2975 14125);
FORCEPROP 1 LAST PACK_TYPE 0402LF
J 0
(-2650 14200);
DISPLAY 0.638298 (-2650 14200);
FORCEPROP 2 LAST CDS_LIB pure_quanta
J 0
(-2825 14275);
DISPLAY INVISIBLE (-2825 14275);
FORCEPROP 1 LAST PATH I17
J 0
(-2875 14425);
DISPLAY 0.978723 (-2875 14425);
PAINT WHITE (-2875 14425);
DISPLAY INVISIBLE (-2875 14425);
FORCEPROP 1 LAST PART_NUMBER CS00002JB13
J 0
(-3075 14200);
DISPLAY 0.638298 (-3075 14200);
DISPLAY INVISIBLE (-3075 14200);
FORCEADD Q_RES..2
(-2525 14550);
FORCEPROP 1 LAST LOCATION R1857
J 0
(-2480 14675);
DISPLAY 0.787234 (-2480 14675);
FORCEPROP 0 LAST $SEC 1
J 0
(-2475 14725);
DISPLAY 0.680851 (-2475 14725);
PAINT MONO (-2475 14725);
DISPLAY INVISIBLE (-2475 14725);
FORCEPROP 0 LAST CDS_SEC 1
J 0
(-2475 14725);
DISPLAY 1.021277 (-2475 14725);
DISPLAY INVISIBLE (-2475 14725);
FORCEPROP 1 LASTPIN (-2525 14650) $PN 1
J 0
(-2520 14612);
DISPLAY 0.787234 (-2520 14612);
PAINT MONO (-2520 14612);
FORCEPROP 1 LASTPIN (-2525 14450) $PN 2
J 0
(-2520 14460);
DISPLAY 0.787234 (-2520 14460);
PAINT MONO (-2520 14460);
FORCEPROP 1 LAST VALUE 10K
J 0
(-2480 14625);
DISPLAY 0.510638 (-2480 14625);
FORCEPROP 1 LAST WATTAGE 1/16W
J 0
(-2485 14525);
DISPLAY 0.510638 (-2485 14525);
FORCEPROP 1 LAST MATERIAL CHIP
J 0
(-2485 14475);
DISPLAY 0.510638 (-2485 14475);
FORCEPROP 1 LAST TOLERANCE 1%
J 0
(-2480 14575);
DISPLAY 0.510638 (-2480 14575);
FORCEPROP 1 LAST PACK_TYPE 0402LF
J 0
(-2485 14375);
DISPLAY 0.510638 (-2485 14375);
FORCEPROP 2 LAST CDS_LIB pure_quanta
J 2
(-2525 14550);
DISPLAY INVISIBLE (-2525 14550);
FORCEPROP 1 LAST PATH I18
J 0
(-2475 14725);
DISPLAY 0.978723 (-2475 14725);
PAINT WHITE (-2475 14725);
DISPLAY INVISIBLE (-2475 14725);
FORCEPROP 1 LAST PART_NUMBER CS31002FB08
J 0
(-2485 14425);
DISPLAY 0.510638 (-2485 14425);
DISPLAY INVISIBLE (-2485 14425);
FORCEADD UNIVERSAL_POWER..1
(-2525 14800);
FORCEPROP 3 LASTPIN (-2525 14750) SIG_NAME P3V3_AUX\g
J 0
(-2515 14760);
DISPLAY 0.659574 (-2515 14760);
PAINT MONO (-2515 14760);
DISPLAY INVISIBLE (-2515 14760);
FORCEPROP 1 LAST HDL_POWER P3V3_AUX
J 1
(-2525 14850);
DISPLAY 0.702128 (-2525 14850);
PAINT GREEN (-2525 14850);
FORCEPROP 2 LAST CDS_LIB pure_quanta_power
J 0
(-2525 14800);
DISPLAY INVISIBLE (-2525 14800);
FORCEPROP 1 LAST PATH I19
J 0
(-2475 14825);
DISPLAY 0.872340 (-2475 14825);
PAINT AQUA (-2475 14825);
DISPLAY INVISIBLE (-2475 14825);
FORCEADD Q_RES..2
R 2
(-2750 13400);
FORCEPROP 1 LAST LOCATION R1854
J 2
(-2795 13525);
DISPLAY 0.978723 (-2795 13525);
FORCEPROP 0 LAST $SEC 1
J 0
(-2775 13575);
DISPLAY 0.680851 (-2775 13575);
PAINT MONO (-2775 13575);
DISPLAY INVISIBLE (-2775 13575);
FORCEPROP 0 LAST CDS_SEC 1
J 0
(-2775 13575);
DISPLAY 1.021277 (-2775 13575);
DISPLAY INVISIBLE (-2775 13575);
FORCEPROP 1 LASTPIN (-2750 13500) $PN 1
J 2
(-2755 13462);
DISPLAY 0.787234 (-2755 13462);
PAINT MONO (-2755 13462);
FORCEPROP 1 LASTPIN (-2750 13300) $PN 2
J 2
(-2755 13310);
DISPLAY 0.787234 (-2755 13310);
PAINT MONO (-2755 13310);
FORCEPROP 1 LAST VALUE 1K
J 2
(-2795 13475);
DISPLAY 0.510638 (-2795 13475);
FORCEPROP 1 LAST WATTAGE 1/16W
J 2
(-2790 13375);
DISPLAY 0.510638 (-2790 13375);
FORCEPROP 1 LAST TOLERANCE 1%
J 2
(-2795 13425);
DISPLAY 0.510638 (-2795 13425);
FORCEPROP 1 LAST MATERIAL CHIP
J 2
(-2790 13325);
DISPLAY 0.510638 (-2790 13325);
FORCEPROP 1 LAST PACK_TYPE 0402LF
J 2
(-2790 13225);
DISPLAY 0.510638 (-2790 13225);
FORCEPROP 2 LAST CDS_LIB pure_quanta
J 0
(-2750 13400);
DISPLAY INVISIBLE (-2750 13400);
FORCEPROP 1 LAST PATH I2
J 2
(-2800 13575);
DISPLAY 0.978723 (-2800 13575);
PAINT WHITE (-2800 13575);
DISPLAY INVISIBLE (-2800 13575);
FORCEPROP 1 LAST PART_NUMBER CS21002FB06
J 2
(-2790 13275);
DISPLAY 0.510638 (-2790 13275);
DISPLAY INVISIBLE (-2790 13275);
FORCEADD Q_RES..1
(-2025 14275);
FORCEPROP 1 LAST LOCATION R4062
J 0
(-2175 14275);
DISPLAY 0.638298 (-2175 14275);
FORCEPROP 0 LAST $SEC 1
J 0
(-1950 14350);
DISPLAY INVISIBLE (-1950 14350);
FORCEPROP 0 LAST CDS_SEC 1
J 0
(-1950 14350);
DISPLAY INVISIBLE (-1950 14350);
FORCEPROP 1 LASTPIN (-2125 14275) $PN 1
J 0
(-2113 14287);
DISPLAY 0.787234 (-2113 14287);
PAINT MONO (-2113 14287);
DISPLAY INVISIBLE (-2113 14287);
FORCEPROP 1 LASTPIN (-1925 14275) $PN 2
J 0
(-1963 14287);
DISPLAY 0.787234 (-1963 14287);
PAINT MONO (-1963 14287);
DISPLAY INVISIBLE (-1963 14287);
FORCEPROP 1 LAST PACK_TYPE 0402LF
J 0
(-1950 14200);
DISPLAY 0.595745 (-1950 14200);
FORCEPROP 1 LAST WATTAGE 1/16W
J 2
(-1825 14150);
DISPLAY 0.595745 (-1825 14150);
FORCEPROP 1 LAST TOLERANCE 5%
J 0
(-1850 14275);
DISPLAY 0.595745 (-1850 14275);
FORCEPROP 1 LAST MATERIAL CHIP
J 0
(-2150 14150);
DISPLAY 0.595745 (-2150 14150);
FORCEPROP 1 LAST VALUE 0
J 2
(-1875 14275);
DISPLAY 0.595745 (-1875 14275);
FORCEPROP 0 LAST ROOM SCM_P12V_MAM_BOM1
J 0
(-2250 14100);
DISPLAY 0.680851 (-2250 14100);
PAINT RED (-2250 14100);
FORCEPROP 2 LAST CDS_LIB pure_quanta
J 0
(-2025 14275);
DISPLAY INVISIBLE (-2025 14275);
FORCEPROP 1 LAST PATH I20
J 0
(-2075 14425);
DISPLAY 0.978723 (-2075 14425);
PAINT WHITE (-2075 14425);
DISPLAY INVISIBLE (-2075 14425);
FORCEPROP 1 LAST PART_NUMBER CS00002JB13
J 0
(-2325 14200);
DISPLAY 0.595745 (-2325 14200);
DISPLAY INVISIBLE (-2325 14200);
FORCEADD GND..1
(-1125 13975);
FORCEPROP 3 LASTPIN (-1125 14025) SIG_NAME GND\g
J 0
(-1115 14035);
DISPLAY 0.659574 (-1115 14035);
PAINT MONO (-1115 14035);
DISPLAY INVISIBLE (-1115 14035);
FORCEPROP 1 LAST SIZE 1B
J 0
(-1050 13925);
DISPLAY 0.872340 (-1050 13925);
PAINT GREEN (-1050 13925);
DISPLAY INVISIBLE (-1050 13925);
FORCEPROP 2 LAST CDS_LIB pure_quanta_power
J 0
(-1125 13975);
DISPLAY INVISIBLE (-1125 13975);
FORCEPROP 1 LAST HDL_POWER GND
J 0
(-1125 14125);
DISPLAY 0.872340 (-1125 14125);
PAINT GREEN (-1125 14125);
DISPLAY INVISIBLE (-1125 14125);
FORCEPROP 1 LAST PATH I21
J 0
(-1050 13975);
DISPLAY 0.872340 (-1050 13975);
PAINT AQUA (-1050 13975);
DISPLAY INVISIBLE (-1050 13975);
FORCEADD MOSFET_NCH_DUAL..1
(-1175 14325);
FORCEPROP 1 LAST LOCATION Q125
J 0
(-1024 14299);
DISPLAY 0.723404 (-1024 14299);
PAINT GREEN (-1024 14299);
FORCEPROP 0 LAST $SEC 1
J 0
(-1000 14450);
DISPLAY 0.680851 (-1000 14450);
PAINT MONO (-1000 14450);
DISPLAY INVISIBLE (-1000 14450);
FORCEPROP 0 LAST CDS_SEC 1
J 0
(-1000 14450);
DISPLAY 1.021277 (-1000 14450);
DISPLAY INVISIBLE (-1000 14450);
FORCEPROP 0 LASTPIN (-1125 14525) $PN 6
R 1
J 0
(-1135 14535);
DISPLAY 0.680851 (-1135 14535);
PAINT MONO (-1135 14535);
FORCEPROP 0 LASTPIN (-1375 14275) $PN 2
J 2
(-1385 14285);
DISPLAY 0.680851 (-1385 14285);
PAINT MONO (-1385 14285);
FORCEPROP 0 LASTPIN (-1125 14125) $PN 1
R 1
J 2
(-1135 14115);
DISPLAY 0.680851 (-1135 14115);
PAINT MONO (-1135 14115);
FORCEPROP 1 LAST MATERIAL IC
J 0
(-1024 14174);
DISPLAY 0.723404 (-1024 14174);
PAINT GREEN (-1024 14174);
FORCEPROP 2 LAST PART_TYPE SMLF
J 0
(-1000 14400);
DISPLAY 1.021277 (-1000 14400);
FORCEPROP 2 LAST VALUE PJT138K
J 0
(-1000 14350);
DISPLAY 1.021277 (-1000 14350);
FORCEPROP 0 LAST ROOM SCM_P12V_MAM_BOM1
J 0
(-1025 14125);
DISPLAY 0.553191 (-1025 14125);
PAINT RED (-1025 14125);
FORCEPROP 2 LAST CDS_LIB pure_quanta
J 0
(-1175 14325);
DISPLAY INVISIBLE (-1175 14325);
FORCEPROP 1 LAST CDS_LMAN_SYM_OUTLINE -150,150,150,-150
J 0
(-1175 14325);
DISPLAY 0.468085 (-1175 14325);
PAINT GREEN (-1175 14325);
DISPLAY INVISIBLE (-1175 14325);
FORCEPROP 1 LAST NEEDS_NO_SIZE TRUE
J 0
(-1175 14324);
DISPLAY 0.468085 (-1175 14324);
PAINT GREEN (-1175 14324);
DISPLAY INVISIBLE (-1175 14324);
FORCEPROP 1 LAST PATH I22
J 0
(-1175 14325);
DISPLAY 0.723404 (-1175 14325);
PAINT GREEN (-1175 14325);
DISPLAY INVISIBLE (-1175 14325);
FORCEPROP 1 LAST PART_NUMBER BAM138K0003
J 0
(-1024 14239);
DISPLAY 0.723404 (-1024 14239);
PAINT GREEN (-1024 14239);
DISPLAY INVISIBLE (-1024 14239);
FORCEADD GND..1
(-450 14350);
FORCEPROP 3 LASTPIN (-450 14400) SIG_NAME GND\g
J 0
(-440 14410);
DISPLAY 0.659574 (-440 14410);
PAINT MONO (-440 14410);
DISPLAY INVISIBLE (-440 14410);
FORCEPROP 2 LAST CDS_LIB pure_quanta_power
J 0
(-450 14350);
DISPLAY INVISIBLE (-450 14350);
FORCEPROP 1 LAST SIZE 1B
J 0
(-375 14300);
DISPLAY 0.872340 (-375 14300);
PAINT GREEN (-375 14300);
DISPLAY INVISIBLE (-375 14300);
FORCEPROP 1 LAST HDL_POWER GND
J 0
(-450 14500);
DISPLAY 0.872340 (-450 14500);
PAINT GREEN (-450 14500);
DISPLAY INVISIBLE (-450 14500);
FORCEPROP 1 LAST PATH I23
J 0
(-375 14350);
DISPLAY 0.872340 (-375 14350);
PAINT AQUA (-375 14350);
DISPLAY INVISIBLE (-375 14350);
FORCEADD MOSFET_NCH_DUAL..2
(-500 14675);
FORCEPROP 1 LAST LOCATION Q125
J 0
(-349 14651);
DISPLAY 0.723404 (-349 14651);
PAINT GREEN (-349 14651);
FORCEPROP 0 LAST $SEC 2
J 0
(-325 14800);
DISPLAY 0.680851 (-325 14800);
PAINT MONO (-325 14800);
DISPLAY INVISIBLE (-325 14800);
FORCEPROP 0 LAST CDS_SEC 2
J 0
(-325 14800);
DISPLAY 1.021277 (-325 14800);
DISPLAY INVISIBLE (-325 14800);
FORCEPROP 0 LASTPIN (-450 14875) $PN 3
R 1
J 0
(-460 14885);
DISPLAY 0.680851 (-460 14885);
PAINT MONO (-460 14885);
FORCEPROP 0 LASTPIN (-700 14625) $PN 5
J 2
(-710 14635);
DISPLAY 0.680851 (-710 14635);
PAINT MONO (-710 14635);
FORCEPROP 0 LASTPIN (-450 14475) $PN 4
R 1
J 2
(-460 14465);
DISPLAY 0.680851 (-460 14465);
PAINT MONO (-460 14465);
FORCEPROP 0 LAST ROOM SCM_P12V_MAM_BOM1
J 0
(-350 14475);
DISPLAY 0.553191 (-350 14475);
PAINT RED (-350 14475);
FORCEPROP 2 LAST VALUE PJT138K
J 0
(-325 14700);
DISPLAY 1.021277 (-325 14700);
FORCEPROP 2 LAST PART_TYPE SMLF
J 0
(-325 14750);
DISPLAY 1.021277 (-325 14750);
FORCEPROP 1 LAST MATERIAL IC
J 0
(-349 14526);
DISPLAY 0.723404 (-349 14526);
PAINT GREEN (-349 14526);
FORCEPROP 1 LAST NEEDS_NO_SIZE TRUE
J 0
(-350 14566);
DISPLAY 0.468085 (-350 14566);
PAINT GREEN (-350 14566);
DISPLAY INVISIBLE (-350 14566);
FORCEPROP 1 LAST CDS_LMAN_SYM_OUTLINE -150,150,150,-150
J 0
(-500 14675);
DISPLAY 0.468085 (-500 14675);
PAINT GREEN (-500 14675);
DISPLAY INVISIBLE (-500 14675);
FORCEPROP 2 LAST CDS_LIB pure_quanta
J 0
(-500 14675);
DISPLAY INVISIBLE (-500 14675);
FORCEPROP 1 LAST PATH I24
J 0
(-350 14525);
DISPLAY 0.723404 (-350 14525);
PAINT GREEN (-350 14525);
DISPLAY INVISIBLE (-350 14525);
FORCEPROP 1 LAST PART_NUMBER BAM138K0003
J 0
(-349 14581);
DISPLAY 0.723404 (-349 14581);
PAINT GREEN (-349 14581);
DISPLAY INVISIBLE (-349 14581);
FORCEADD Q_RES..2
(-1125 14925);
FORCEPROP 1 LAST LOCATION R4071
J 0
(-1090 15092);
DISPLAY 0.638298 (-1090 15092);
FORCEPROP 0 LAST $SEC 1
J 0
(-1075 15125);
DISPLAY 0.680851 (-1075 15125);
PAINT MONO (-1075 15125);
DISPLAY INVISIBLE (-1075 15125);
FORCEPROP 0 LAST CDS_SEC 1
J 0
(-1075 15125);
DISPLAY 1.021277 (-1075 15125);
DISPLAY INVISIBLE (-1075 15125);
FORCEPROP 1 LASTPIN (-1125 15025) $PN 1
J 0
(-1120 14987);
DISPLAY 0.787234 (-1120 14987);
PAINT MONO (-1120 14987);
FORCEPROP 1 LASTPIN (-1125 14825) $PN 2
J 0
(-1120 14835);
DISPLAY 0.787234 (-1120 14835);
PAINT MONO (-1120 14835);
FORCEPROP 1 LAST WATTAGE 1/16W
J 0
(-1095 14942);
DISPLAY 0.638298 (-1095 14942);
FORCEPROP 1 LAST VALUE 10K
J 0
(-1090 15042);
DISPLAY 0.638298 (-1090 15042);
FORCEPROP 1 LAST MATERIAL CHIP
J 0
(-1095 14892);
DISPLAY 0.638298 (-1095 14892);
FORCEPROP 1 LAST TOLERANCE 1%
J 0
(-1090 14992);
DISPLAY 0.638298 (-1090 14992);
FORCEPROP 1 LAST PACK_TYPE 0402LF
J 0
(-1095 14792);
DISPLAY 0.638298 (-1095 14792);
FORCEPROP 0 LAST ROOM SCM_P12V_MAM_BOM1
J 0
(-1075 15150);
DISPLAY 0.553191 (-1075 15150);
PAINT RED (-1075 15150);
FORCEPROP 2 LAST CDS_LIB pure_quanta
J 0
(-1125 14925);
DISPLAY INVISIBLE (-1125 14925);
FORCEPROP 1 LAST PATH I25
J 0
(-1075 15100);
DISPLAY 0.978723 (-1075 15100);
PAINT WHITE (-1075 15100);
DISPLAY INVISIBLE (-1075 15100);
FORCEPROP 1 LAST PART_NUMBER CS31002FB08
J 0
(-1095 14842);
DISPLAY 0.638298 (-1095 14842);
DISPLAY INVISIBLE (-1095 14842);
FORCEADD UNIVERSAL_POWER..1
(-1125 15175);
FORCEPROP 3 LASTPIN (-1125 15125) SIG_NAME P12V_AUX\g
J 0
(-1115 15135);
DISPLAY 0.659574 (-1115 15135);
PAINT MONO (-1115 15135);
DISPLAY INVISIBLE (-1115 15135);
FORCEPROP 1 LAST HDL_POWER P12V_AUX
J 1
(-1125 15225);
DISPLAY 0.872340 (-1125 15225);
PAINT GREEN (-1125 15225);
FORCEPROP 2 LAST CDS_LIB pure_quanta_power
J 0
(-1125 15175);
DISPLAY INVISIBLE (-1125 15175);
FORCEPROP 1 LAST PATH I26
J 0
(-1075 15200);
DISPLAY 0.872340 (-1075 15200);
PAINT AQUA (-1075 15200);
DISPLAY INVISIBLE (-1075 15200);
FORCEADD Q_RES..1
(100 15000);
FORCEPROP 1 LAST LOCATION R3997
J 0
(50 15050);
DISPLAY 0.978723 (50 15050);
FORCEPROP 0 LAST $SEC 1
J 0
(50 15100);
DISPLAY 0.680851 (50 15100);
PAINT MONO (50 15100);
DISPLAY INVISIBLE (50 15100);
FORCEPROP 0 LAST CDS_SEC 1
J 0
(50 15100);
DISPLAY 1.021277 (50 15100);
DISPLAY INVISIBLE (50 15100);
FORCEPROP 1 LASTPIN (0 15000) $PN 1
J 0
(12 15012);
DISPLAY 0.787234 (12 15012);
PAINT MONO (12 15012);
FORCEPROP 1 LASTPIN (200 15000) $PN 2
J 0
(162 15012);
DISPLAY 0.787234 (162 15012);
PAINT MONO (162 15012);
FORCEPROP 1 LAST WATTAGE 1/16W
J 2
(300 14900);
DISPLAY 0.510638 (300 14900);
FORCEPROP 1 LAST TOLERANCE 5%
J 0
(275 15000);
DISPLAY 0.510638 (275 15000);
FORCEPROP 1 LAST PACK_TYPE 0402LF
J 0
(375 15000);
DISPLAY 0.510638 (375 15000);
FORCEPROP 1 LAST MATERIAL CHIP
J 0
(25 14900);
DISPLAY 0.510638 (25 14900);
FORCEPROP 1 LAST VALUE 0
J 2
(250 15000);
DISPLAY 0.510638 (250 15000);
FORCEPROP 0 LAST ROOM SCM_P12V_MAM_BOM1
J 0
(-50 15125);
DISPLAY 0.553191 (-50 15125);
PAINT RED (-50 15125);
FORCEPROP 2 LAST CDS_LIB pure_quanta
J 0
(100 15000);
DISPLAY INVISIBLE (100 15000);
FORCEPROP 1 LAST PATH I27
J 0
(50 15150);
DISPLAY 0.978723 (50 15150);
PAINT WHITE (50 15150);
DISPLAY INVISIBLE (50 15150);
FORCEPROP 1 LAST PART_NUMBER CS00002JB13
J 0
(25 14950);
DISPLAY 0.510638 (25 14950);
DISPLAY INVISIBLE (25 14950);
FORCEADD DIODE_TVS..1
R 1
(-50 15650);
FORCEPROP 1 LAST LOCATION PD115
J 0
(5 15692);
DISPLAY 0.574468 (5 15692);
PAINT GREEN (5 15692);
FORCEPROP 0 LAST $SEC 1
R 1
J 0
(5 15742);
DISPLAY INVISIBLE (5 15742);
FORCEPROP 0 LAST CDS_SEC 1
R 1
J 0
(5 15742);
DISPLAY INVISIBLE (5 15742);
FORCEPROP 0 LASTPIN (-50 15500) $PN A
R 1
J 2
(-60 15490);
DISPLAY 0.808511 (-60 15490);
FORCEPROP 0 LASTPIN (-50 15800) $PN C
R 1
J 0
(-60 15810);
DISPLAY 0.808511 (-60 15810);
FORCEPROP 2 LAST VALUE SMF14A
J 0
(0 15625);
DISPLAY 0.574468 (0 15625);
PAINT SKYBLUE (0 15625);
FORCEPROP 1 LAST MATERIAL IC
J 0
(0 15500);
DISPLAY 0.723404 (0 15500);
PAINT GREEN (0 15500);
FORCEPROP 0 LAST PART_TYPE SMLF
J 0
(50 15775);
DISPLAY 1.021277 (50 15775);
FORCEPROP 1 LASTPIN (-50 15800) Pin_Length SHORT
R 1
J 0
(-40 15825);
DISPLAY 0.489362 (-40 15825);
PAINT MONO (-40 15825);
DISPLAY INVISIBLE (-40 15825);
FORCEPROP 1 LAST CDS_LMAN_SYM_OUTLINE -100,50,100,-50
R 1
J 0
(-50 15650);
DISPLAY 0.468085 (-50 15650);
PAINT GREEN (-50 15650);
DISPLAY INVISIBLE (-50 15650);
FORCEPROP 2 LAST CDS_LIB pure_quanta
J 0
(-50 15650);
DISPLAY INVISIBLE (-50 15650);
FORCEPROP 1 LAST PIN_NAMES_ROTATE TRUE
R 1
J 0
(-50 15650);
DISPLAY 0.489362 (-50 15650);
PAINT GREEN (-50 15650);
DISPLAY INVISIBLE (-50 15650);
FORCEPROP 1 LAST PATH I28
R 1
J 0
(0 15750);
DISPLAY 0.723404 (0 15750);
PAINT GREEN (0 15750);
DISPLAY INVISIBLE (0 15750);
FORCEPROP 1 LAST PART_NUMBER BCSMF14AZ01
J 0
(5 15567);
DISPLAY 0.574468 (5 15567);
PAINT GREEN (5 15567);
DISPLAY INVISIBLE (5 15567);
FORCEADD GND..1
(100 15250);
FORCEPROP 3 LASTPIN (100 15300) SIG_NAME GND\g
J 0
(110 15310);
DISPLAY 0.659574 (110 15310);
PAINT MONO (110 15310);
DISPLAY INVISIBLE (110 15310);
FORCEPROP 2 LAST CDS_LIB pure_quanta_power
J 0
(100 15250);
DISPLAY INVISIBLE (100 15250);
FORCEPROP 1 LAST SIZE 1B
J 0
(175 15200);
DISPLAY 0.872340 (175 15200);
PAINT GREEN (175 15200);
DISPLAY INVISIBLE (175 15200);
FORCEPROP 1 LAST HDL_POWER GND
J 0
(100 15400);
DISPLAY 0.872340 (100 15400);
PAINT GREEN (100 15400);
DISPLAY INVISIBLE (100 15400);
FORCEPROP 1 LAST PATH I29
J 0
(175 15250);
DISPLAY 0.872340 (175 15250);
PAINT AQUA (175 15250);
DISPLAY INVISIBLE (175 15250);
FORCEADD Q_RES..1
(-1800 13175);
FORCEPROP 1 LAST LOCATION R1856
J 0
(-2025 13175);
DISPLAY 0.638298 (-2025 13175);
FORCEPROP 0 LAST $SEC 1
J 0
(-1575 13350);
DISPLAY 0.680851 (-1575 13350);
PAINT MONO (-1575 13350);
DISPLAY INVISIBLE (-1575 13350);
FORCEPROP 0 LAST CDS_SEC 1
J 0
(-1575 13350);
DISPLAY 1.021277 (-1575 13350);
DISPLAY INVISIBLE (-1575 13350);
FORCEPROP 1 LASTPIN (-1900 13175) $PN 1
J 0
(-1888 13187);
DISPLAY 0.787234 (-1888 13187);
PAINT MONO (-1888 13187);
FORCEPROP 1 LASTPIN (-1700 13175) $PN 2
J 0
(-1738 13187);
DISPLAY 0.787234 (-1738 13187);
PAINT MONO (-1738 13187);
FORCEPROP 1 LAST TOLERANCE 1%
J 0
(-1600 13175);
DISPLAY 0.510638 (-1600 13175);
FORCEPROP 1 LAST VALUE 100
J 2
(-1625 13175);
DISPLAY 0.510638 (-1625 13175);
FORCEPROP 1 LAST PACK_TYPE 0402LF
J 0
(-2000 13325);
DISPLAY 0.510638 (-2000 13325);
FORCEPROP 1 LAST MATERIAL CHIP
J 0
(-1825 13325);
DISPLAY 0.510638 (-1825 13325);
FORCEPROP 1 LAST WATTAGE 1/16W
J 2
(-1575 13325);
DISPLAY 0.510638 (-1575 13325);
FORCEPROP 2 LAST CDS_LIB pure_quanta
J 0
(-1800 13175);
DISPLAY INVISIBLE (-1800 13175);
FORCEPROP 1 LAST PATH I3
J 0
(-1850 13325);
DISPLAY 0.978723 (-1850 13325);
PAINT WHITE (-1850 13325);
DISPLAY INVISIBLE (-1850 13325);
FORCEPROP 1 LAST PART_NUMBER CS11002FB07
J 0
(-2000 13275);
DISPLAY 0.510638 (-2000 13275);
DISPLAY INVISIBLE (-2000 13275);
FORCEADD UNIVERSAL_POWER..1
(100 15975);
FORCEPROP 3 LASTPIN (100 15925) SIG_NAME P12V_AUX\g
J 0
(110 15935);
DISPLAY 0.659574 (110 15935);
PAINT MONO (110 15935);
DISPLAY INVISIBLE (110 15935);
FORCEPROP 1 LAST HDL_POWER P12V_AUX
J 1
(100 16025);
DISPLAY 0.872340 (100 16025);
PAINT GREEN (100 16025);
FORCEPROP 2 LAST CDS_LIB pure_quanta_power
J 0
(100 15975);
DISPLAY INVISIBLE (100 15975);
FORCEPROP 1 LAST PATH I30
J 0
(150 16000);
DISPLAY 0.872340 (150 16000);
PAINT AQUA (150 16000);
DISPLAY INVISIBLE (150 16000);
FORCEADD Q_CAP..1
(325 15625);
FORCEPROP 1 LAST LOCATION PC2230
J 0
(375 15700);
DISPLAY 0.638298 (375 15700);
FORCEPROP 0 LAST $SEC 1
J 0
(380 15767);
DISPLAY INVISIBLE (380 15767);
FORCEPROP 0 LAST CDS_SEC 1
J 0
(380 15767);
DISPLAY INVISIBLE (380 15767);
FORCEPROP 1 LASTPIN (325 15725) $PN 1
J 0
(335 15705);
DISPLAY 0.787234 (335 15705);
PAINT MONO (335 15705);
DISPLAY INVISIBLE (335 15705);
FORCEPROP 1 LASTPIN (325 15525) $PN 2
J 0
(335 15505);
DISPLAY 0.787234 (335 15505);
PAINT MONO (335 15505);
DISPLAY INVISIBLE (335 15505);
FORCEPROP 1 LAST MATERIAL X6S
J 0
(375 15625);
DISPLAY 0.510638 (375 15625);
FORCEPROP 1 LAST VALUE 1UF
J 0
(375 15675);
DISPLAY 0.510638 (375 15675);
FORCEPROP 1 LAST VOLTAGE 25V
J 0
(375 15650);
DISPLAY 0.510638 (375 15650);
FORCEPROP 1 LAST PACK_TYPE C0402
J 0
(375 15600);
DISPLAY 0.510638 (375 15600);
FORCEPROP 1 LAST TOLERANCE 10%
J 0
(375 15575);
DISPLAY 0.638298 (375 15575);
DISPLAY INVISIBLE (375 15575);
FORCEPROP 2 LAST CDS_LIB pure_quanta
J 0
(325 15625);
DISPLAY INVISIBLE (325 15625);
FORCEPROP 1 LAST PATH I31
J 0
(375 15775);
DISPLAY 0.978723 (375 15775);
PAINT WHITE (375 15775);
DISPLAY INVISIBLE (375 15775);
FORCEPROP 1 LAST PART_NUMBER CH5104KEB02
J 0
(375 15575);
DISPLAY 0.510638 (375 15575);
DISPLAY INVISIBLE (375 15575);
FORCEADD GND..1
(825 11250);
FORCEPROP 3 LASTPIN (825 11300) SIG_NAME GND\g
J 0
(835 11310);
DISPLAY 0.659574 (835 11310);
PAINT MONO (835 11310);
DISPLAY INVISIBLE (835 11310);
FORCEPROP 1 LAST SIZE 1B
J 0
(900 11200);
DISPLAY 0.872340 (900 11200);
PAINT GREEN (900 11200);
DISPLAY INVISIBLE (900 11200);
FORCEPROP 2 LAST CDS_LIB pure_quanta_power
J 0
(825 11250);
DISPLAY INVISIBLE (825 11250);
FORCEPROP 1 LAST HDL_POWER GND
J 0
(825 11400);
DISPLAY 0.872340 (825 11400);
PAINT GREEN (825 11400);
DISPLAY INVISIBLE (825 11400);
FORCEPROP 1 LAST PATH I32
J 0
(900 11250);
DISPLAY 0.872340 (900 11250);
PAINT AQUA (900 11250);
DISPLAY INVISIBLE (900 11250);
FORCEADD Q_CAP..1
(825 11475);
FORCEPROP 1 LAST LOCATION PC2232
J 0
(875 11525);
DISPLAY 0.638298 (875 11525);
FORCEPROP 0 LAST $SEC 1
J 0
(875 11625);
DISPLAY INVISIBLE (875 11625);
FORCEPROP 0 LAST CDS_SEC 1
J 0
(875 11625);
DISPLAY INVISIBLE (875 11625);
FORCEPROP 1 LASTPIN (825 11575) $PN 1
J 0
(835 11555);
DISPLAY 0.787234 (835 11555);
PAINT MONO (835 11555);
DISPLAY INVISIBLE (835 11555);
FORCEPROP 1 LASTPIN (825 11375) $PN 2
J 0
(835 11355);
DISPLAY 0.787234 (835 11355);
PAINT MONO (835 11355);
DISPLAY INVISIBLE (835 11355);
FORCEPROP 0 LAST ROOM SCM_P12V_MPS_BOM2
J 0
(875 11375);
DISPLAY 0.446809 (875 11375);
PAINT RED (875 11375);
FORCEPROP 1 LAST VOLTAGE 25V
J 0
(875 11475);
DISPLAY 0.510638 (875 11475);
FORCEPROP 1 LAST MATERIAL X7R
J 0
(875 11450);
DISPLAY 0.510638 (875 11450);
PAINT RED (875 11450);
FORCEPROP 1 LAST PACK_TYPE C0402
J 0
(875 11400);
DISPLAY 0.510638 (875 11400);
FORCEPROP 1 LAST VALUE 0.047UF
J 0
(875 11500);
DISPLAY 0.510638 (875 11500);
FORCEPROP 2 LAST CDS_LIB pure_quanta
J 0
(825 11475);
DISPLAY INVISIBLE (825 11475);
FORCEPROP 1 LAST TOLERANCE 10%
J 0
(875 11425);
DISPLAY 0.638298 (875 11425);
DISPLAY INVISIBLE (875 11425);
FORCEPROP 1 LAST PATH I33
J 0
(875 11625);
DISPLAY 0.978723 (875 11625);
PAINT WHITE (875 11625);
DISPLAY INVISIBLE (875 11625);
FORCEPROP 1 LAST PART_NUMBER CH3474K1B04
J 0
(875 11425);
DISPLAY 0.510638 (875 11425);
DISPLAY INVISIBLE (875 11425);
FORCEADD GND..1
(1166 11416);
FORCEPROP 3 LASTPIN (1166 11466) SIG_NAME GND\g
J 0
(1176 11476);
DISPLAY 0.659574 (1176 11476);
PAINT MONO (1176 11476);
DISPLAY INVISIBLE (1176 11476);
FORCEPROP 2 LAST CDS_LIB pure_quanta_power
J 0
(1166 11416);
DISPLAY INVISIBLE (1166 11416);
FORCEPROP 1 LAST SIZE 1B
J 0
(1241 11366);
DISPLAY 0.872340 (1241 11366);
PAINT GREEN (1241 11366);
DISPLAY INVISIBLE (1241 11366);
FORCEPROP 1 LAST HDL_POWER GND
J 0
(1166 11566);
DISPLAY 0.872340 (1166 11566);
PAINT GREEN (1166 11566);
DISPLAY INVISIBLE (1166 11566);
FORCEPROP 1 LAST PATH I34
J 0
(1241 11416);
DISPLAY 0.872340 (1241 11416);
PAINT AQUA (1241 11416);
DISPLAY INVISIBLE (1241 11416);
FORCEADD Q_RES..2
(2250 11275);
FORCEPROP 1 LAST LOCATION PR4005
J 0
(2300 11325);
DISPLAY 0.638298 (2300 11325);
FORCEPROP 0 LAST $SEC 1
J 0
(2300 11450);
DISPLAY 0.680851 (2300 11450);
PAINT MONO (2300 11450);
DISPLAY INVISIBLE (2300 11450);
FORCEPROP 0 LAST CDS_SEC 1
J 0
(2300 11450);
DISPLAY 1.021277 (2300 11450);
DISPLAY INVISIBLE (2300 11450);
FORCEPROP 1 LASTPIN (2250 11375) $PN 1
J 0
(2255 11337);
DISPLAY 0.787234 (2255 11337);
PAINT MONO (2255 11337);
FORCEPROP 1 LASTPIN (2250 11175) $PN 2
J 0
(2255 11185);
DISPLAY 0.787234 (2255 11185);
PAINT MONO (2255 11185);
FORCEPROP 1 LAST WATTAGE 1/16W
J 0
(2300 11250);
DISPLAY 0.510638 (2300 11250);
FORCEPROP 1 LAST TOLERANCE 1%
J 0
(2300 11275);
DISPLAY 0.510638 (2300 11275);
FORCEPROP 1 LAST PACK_TYPE 0402LF
J 0
(2300 11175);
DISPLAY 0.510638 (2300 11175);
FORCEPROP 0 LAST ROOM SCM_P12V_MPS_BOM2
J 0
(2200 11150);
DISPLAY 0.446809 (2200 11150);
PAINT RED (2200 11150);
FORCEPROP 1 LAST MATERIAL CHIP
J 0
(2300 11225);
DISPLAY 0.510638 (2300 11225);
PAINT RED (2300 11225);
FORCEPROP 1 LAST VALUE 30.1K
J 0
(2300 11300);
DISPLAY 0.510638 (2300 11300);
FORCEPROP 2 LAST CDS_LIB pure_quanta
J 0
(2250 11275);
DISPLAY INVISIBLE (2250 11275);
FORCEPROP 1 LAST PATH I35
J 0
(2300 11450);
DISPLAY 0.978723 (2300 11450);
PAINT WHITE (2300 11450);
DISPLAY INVISIBLE (2300 11450);
FORCEPROP 1 LAST PART_NUMBER CS33012FB03
J 0
(2300 11200);
DISPLAY 0.510638 (2300 11200);
DISPLAY INVISIBLE (2300 11200);
FORCEADD GND..1
(750 12325);
FORCEPROP 3 LASTPIN (750 12375) SIG_NAME GND\g
J 0
(760 12385);
DISPLAY 0.659574 (760 12385);
PAINT MONO (760 12385);
DISPLAY INVISIBLE (760 12385);
FORCEPROP 1 LAST SIZE 1B
J 0
(825 12275);
DISPLAY 0.872340 (825 12275);
PAINT GREEN (825 12275);
DISPLAY INVISIBLE (825 12275);
FORCEPROP 2 LAST CDS_LIB pure_quanta_power
J 0
(750 12325);
DISPLAY INVISIBLE (750 12325);
FORCEPROP 1 LAST HDL_POWER GND
J 0
(750 12475);
DISPLAY 0.872340 (750 12475);
PAINT GREEN (750 12475);
DISPLAY INVISIBLE (750 12475);
FORCEPROP 1 LAST PATH I36
J 0
(825 12325);
DISPLAY 0.872340 (825 12325);
PAINT AQUA (825 12325);
DISPLAY INVISIBLE (825 12325);
FORCEADD Q_CAP..1
(750 12550);
FORCEPROP 1 LAST LOCATION PC2231
J 0
(800 12600);
DISPLAY 0.638298 (800 12600);
FORCEPROP 0 LAST $SEC 1
J 0
(805 12692);
DISPLAY INVISIBLE (805 12692);
FORCEPROP 0 LAST CDS_SEC 1
J 0
(805 12692);
DISPLAY INVISIBLE (805 12692);
FORCEPROP 1 LASTPIN (750 12650) $PN 1
J 0
(760 12630);
DISPLAY 0.787234 (760 12630);
PAINT MONO (760 12630);
DISPLAY INVISIBLE (760 12630);
FORCEPROP 1 LASTPIN (750 12450) $PN 2
J 0
(760 12430);
DISPLAY 0.787234 (760 12430);
PAINT MONO (760 12430);
DISPLAY INVISIBLE (760 12430);
FORCEPROP 1 LAST VOLTAGE 25V
J 0
(800 12550);
DISPLAY 0.510638 (800 12550);
FORCEPROP 0 LAST ROOM SCM_P12V_MPS_BOM2
J 0
(800 12650);
DISPLAY 0.553191 (800 12650);
PAINT RED (800 12650);
FORCEPROP 1 LAST VALUE 1UF
J 0
(800 12575);
DISPLAY 0.510638 (800 12575);
FORCEPROP 1 LAST MATERIAL X6S
J 0
(800 12525);
DISPLAY 0.510638 (800 12525);
PAINT RED (800 12525);
FORCEPROP 1 LAST PACK_TYPE C0402
J 0
(800 12475);
DISPLAY 0.510638 (800 12475);
FORCEPROP 2 LAST CDS_LIB pure_quanta
J 0
(750 12550);
DISPLAY INVISIBLE (750 12550);
FORCEPROP 1 LAST TOLERANCE 10%
J 0
(800 12500);
DISPLAY 0.638298 (800 12500);
DISPLAY INVISIBLE (800 12500);
FORCEPROP 1 LAST PATH I37
J 0
(800 12700);
DISPLAY 0.978723 (800 12700);
PAINT WHITE (800 12700);
DISPLAY INVISIBLE (800 12700);
FORCEPROP 1 LAST PART_NUMBER CH5104KEB02
J 0
(800 12500);
DISPLAY 0.510638 (800 12500);
DISPLAY INVISIBLE (800 12500);
FORCEADD UNIVERSAL_POWER..1
(750 12900);
FORCEPROP 3 LASTPIN (750 12850) SIG_NAME P12V_AUX\g
J 0
(760 12860);
DISPLAY 0.659574 (760 12860);
PAINT MONO (760 12860);
DISPLAY INVISIBLE (760 12860);
FORCEPROP 1 LAST HDL_POWER P12V_AUX
J 1
(750 12950);
DISPLAY 0.872340 (750 12950);
PAINT GREEN (750 12950);
FORCEPROP 2 LAST CDS_LIB pure_quanta_power
J 0
(750 12900);
DISPLAY INVISIBLE (750 12900);
FORCEPROP 1 LAST PATH I39
J 0
(800 12925);
DISPLAY 0.872340 (800 12925);
PAINT AQUA (800 12925);
DISPLAY INVISIBLE (800 12925);
FORCEADD GND..1
(-525 11350);
FORCEPROP 3 LASTPIN (-525 11400) SIG_NAME GND\g
J 0
(-515 11410);
DISPLAY 0.659574 (-515 11410);
PAINT MONO (-515 11410);
DISPLAY INVISIBLE (-515 11410);
FORCEPROP 1 LAST SIZE 1B
J 0
(-450 11300);
DISPLAY 0.872340 (-450 11300);
PAINT GREEN (-450 11300);
DISPLAY INVISIBLE (-450 11300);
FORCEPROP 2 LAST CDS_LIB pure_quanta_power
J 0
(-525 11350);
DISPLAY INVISIBLE (-525 11350);
FORCEPROP 1 LAST HDL_POWER GND
J 0
(-525 11500);
DISPLAY 0.872340 (-525 11500);
PAINT GREEN (-525 11500);
DISPLAY INVISIBLE (-525 11500);
FORCEPROP 1 LAST PATH I4
J 0
(-450 11350);
DISPLAY 0.872340 (-450 11350);
PAINT AQUA (-450 11350);
DISPLAY INVISIBLE (-450 11350);
FORCEADD Q_RES..1
(3150 11650);
FORCEPROP 1 LAST LOCATION PR4007
J 0
(3075 11700);
DISPLAY 0.638298 (3075 11700);
FORCEPROP 0 LAST $SEC 1
J 0
(3050 11725);
DISPLAY 0.680851 (3050 11725);
PAINT MONO (3050 11725);
DISPLAY INVISIBLE (3050 11725);
FORCEPROP 0 LAST CDS_SEC 1
J 0
(3100 11800);
DISPLAY INVISIBLE (3100 11800);
FORCEPROP 1 LASTPIN (3050 11650) $PN 1
J 0
(3062 11662);
DISPLAY 0.787234 (3062 11662);
PAINT MONO (3062 11662);
DISPLAY INVISIBLE (3062 11662);
FORCEPROP 1 LASTPIN (3250 11650) $PN 2
J 0
(3212 11662);
DISPLAY 0.787234 (3212 11662);
PAINT MONO (3212 11662);
DISPLAY INVISIBLE (3212 11662);
FORCEPROP 1 LAST VALUE 10K
J 2
(3125 11625);
DISPLAY 0.510638 (3125 11625);
FORCEPROP 1 LAST TOLERANCE 1%
J 0
(3200 11625);
DISPLAY 0.510638 (3200 11625);
FORCEPROP 1 LAST MATERIAL CHIP
J 0
(3275 11625);
DISPLAY 0.404255 (3275 11625);
PAINT RED (3275 11625);
FORCEPROP 1 LAST PACK_TYPE 0402LF
J 0
(3300 11675);
DISPLAY 0.404255 (3300 11675);
FORCEPROP 1 LAST WATTAGE 1/16W
J 2
(3475 11625);
DISPLAY 0.404255 (3475 11625);
FORCEPROP 0 LAST ROOM SCM_P12V_MPS_BOM2
J 0
(3050 11575);
DISPLAY 0.446809 (3050 11575);
PAINT RED (3050 11575);
FORCEPROP 2 LAST CDS_LIB pure_quanta
J 0
(3150 11650);
DISPLAY INVISIBLE (3150 11650);
FORCEPROP 1 LAST PATH I40
J 0
(3100 11800);
DISPLAY 0.978723 (3100 11800);
PAINT WHITE (3100 11800);
DISPLAY INVISIBLE (3100 11800);
FORCEPROP 1 LAST PART_NUMBER CS31002FB08
J 0
(3050 11675);
DISPLAY 0.404255 (3050 11675);
DISPLAY INVISIBLE (3050 11675);
FORCEADD Q_RES..2
(2625 12125);
FORCEPROP 1 LAST LOCATION PR4006
J 0
(2675 12200);
DISPLAY 0.638298 (2675 12200);
FORCEPROP 0 LAST $SEC 1
J 0
(2675 12300);
DISPLAY 0.680851 (2675 12300);
PAINT MONO (2675 12300);
DISPLAY INVISIBLE (2675 12300);
FORCEPROP 0 LAST CDS_SEC 1
J 0
(2675 12300);
DISPLAY 1.021277 (2675 12300);
DISPLAY INVISIBLE (2675 12300);
FORCEPROP 1 LASTPIN (2625 12225) $PN 1
J 0
(2630 12187);
DISPLAY 0.787234 (2630 12187);
PAINT MONO (2630 12187);
FORCEPROP 1 LASTPIN (2625 12025) $PN 2
J 0
(2630 12035);
DISPLAY 0.787234 (2630 12035);
PAINT MONO (2630 12035);
FORCEPROP 1 LAST VALUE 100
J 0
(2670 12175);
DISPLAY 0.510638 (2670 12175);
FORCEPROP 0 LAST ROOM SCM_P12V_MPS_BOM2
J 0
(2675 12250);
DISPLAY 0.553191 (2675 12250);
PAINT RED (2675 12250);
FORCEPROP 1 LAST TOLERANCE 1%
J 0
(2675 12150);
DISPLAY 0.510638 (2675 12150);
FORCEPROP 1 LAST MATERIAL EMPTY
J 0
(2675 12100);
DISPLAY 0.510638 (2675 12100);
PAINT RED (2675 12100);
FORCEPROP 1 LAST PACK_TYPE 0402LF
J 0
(2675 12050);
DISPLAY 0.510638 (2675 12050);
FORCEPROP 1 LAST WATTAGE 1/16W
J 0
(2675 12125);
DISPLAY 0.510638 (2675 12125);
FORCEPROP 2 LAST CDS_LIB pure_quanta
J 0
(2625 12125);
DISPLAY INVISIBLE (2625 12125);
FORCEPROP 1 LAST PATH I41
J 0
(2675 12300);
DISPLAY 0.978723 (2675 12300);
PAINT WHITE (2675 12300);
DISPLAY INVISIBLE (2675 12300);
FORCEPROP 1 LAST PART_NUMBER CS11002FB07
J 0
(2675 12075);
DISPLAY 0.510638 (2675 12075);
DISPLAY INVISIBLE (2675 12075);
FORCEADD VCCAUX15..1
(2875 12950);
FORCEPROP 3 LASTPIN (2875 12900) SIG_NAME P3V3_AUX\g
J 0
(2885 12910);
DISPLAY 0.659574 (2885 12910);
PAINT MONO (2885 12910);
DISPLAY INVISIBLE (2885 12910);
FORCEPROP 1 LAST HDL_POWER P3V3_AUX
J 1
(2875 13000);
DISPLAY 0.723404 (2875 13000);
PAINT GREEN (2875 13000);
FORCEPROP 2 LAST CDS_LIB pure_quanta_power
J 0
(2875 12950);
DISPLAY INVISIBLE (2875 12950);
FORCEPROP 1 LAST PATH I42
J 0
(2925 12975);
DISPLAY 0.872340 (2925 12975);
PAINT AQUA (2925 12975);
DISPLAY INVISIBLE (2925 12975);
FORCEADD Q_RES..2
(2875 12775);
FORCEPROP 1 LAST LOCATION R3836
J 0
(2950 12850);
DISPLAY 0.638298 (2950 12850);
FORCEPROP 0 LAST $SEC 1
J 0
(2930 12992);
DISPLAY 0.680851 (2930 12992);
PAINT MONO (2930 12992);
DISPLAY INVISIBLE (2930 12992);
FORCEPROP 0 LAST CDS_SEC 1
J 0
(2925 12950);
DISPLAY INVISIBLE (2925 12950);
FORCEPROP 1 LASTPIN (2875 12875) $PN 1
J 0
(2880 12837);
DISPLAY 0.787234 (2880 12837);
PAINT MONO (2880 12837);
FORCEPROP 1 LASTPIN (2875 12675) $PN 2
J 0
(2880 12685);
DISPLAY 0.787234 (2880 12685);
PAINT MONO (2880 12685);
FORCEPROP 1 LAST MATERIAL CHIP
J 0
(2950 12750);
DISPLAY 0.510638 (2950 12750);
PAINT RED (2950 12750);
FORCEPROP 1 LAST WATTAGE 1/16W
J 0
(2950 12775);
DISPLAY 0.510638 (2950 12775);
FORCEPROP 1 LAST VALUE 10K
J 0
(2950 12825);
DISPLAY 0.510638 (2950 12825);
FORCEPROP 0 LAST ROOM SCM_P12V_MPS_BOM2
J 0
(2950 12950);
DISPLAY 0.553191 (2950 12950);
PAINT RED (2950 12950);
FORCEPROP 1 LAST TOLERANCE 1%
J 0
(2950 12800);
DISPLAY 0.510638 (2950 12800);
FORCEPROP 1 LAST PACK_TYPE 0402LF
J 0
(2950 12700);
DISPLAY 0.510638 (2950 12700);
FORCEPROP 2 LAST CDS_LIB pure_quanta
J 0
(2875 12775);
DISPLAY INVISIBLE (2875 12775);
FORCEPROP 1 LAST PATH I43
J 0
(2925 12950);
DISPLAY 0.978723 (2925 12950);
PAINT WHITE (2925 12950);
DISPLAY INVISIBLE (2925 12950);
FORCEPROP 1 LAST PART_NUMBER CS31002FB08
J 0
(2950 12725);
DISPLAY 0.510638 (2950 12725);
DISPLAY INVISIBLE (2950 12725);
FORCEADD GND..1
(2600 10875);
FORCEPROP 3 LASTPIN (2600 10925) SIG_NAME GND\g
J 0
(2610 10935);
DISPLAY 0.659574 (2610 10935);
PAINT MONO (2610 10935);
DISPLAY INVISIBLE (2610 10935);
FORCEPROP 1 LAST SIZE 1B
J 0
(2675 10825);
DISPLAY 0.872340 (2675 10825);
PAINT GREEN (2675 10825);
DISPLAY INVISIBLE (2675 10825);
FORCEPROP 2 LAST CDS_LIB pure_quanta_power
J 0
(2600 10875);
DISPLAY INVISIBLE (2600 10875);
FORCEPROP 1 LAST HDL_POWER GND
J 0
(2600 11025);
DISPLAY 0.872340 (2600 11025);
PAINT GREEN (2600 11025);
DISPLAY INVISIBLE (2600 11025);
FORCEPROP 1 LAST PATH I44
J 0
(2675 10875);
DISPLAY 0.872340 (2675 10875);
PAINT AQUA (2675 10875);
DISPLAY INVISIBLE (2675 10875);
FORCEADD Q_CAP..1
(2600 11300);
FORCEPROP 1 LAST LOCATION PC2235
J 0
(2675 11350);
DISPLAY 0.638298 (2675 11350);
FORCEPROP 0 LAST $SEC 1
J 0
(2650 11450);
DISPLAY INVISIBLE (2650 11450);
FORCEPROP 0 LAST CDS_SEC 1
J 0
(2650 11450);
DISPLAY INVISIBLE (2650 11450);
FORCEPROP 1 LASTPIN (2600 11400) $PN 1
J 0
(2610 11380);
DISPLAY 0.787234 (2610 11380);
PAINT MONO (2610 11380);
DISPLAY INVISIBLE (2610 11380);
FORCEPROP 1 LASTPIN (2600 11200) $PN 2
J 0
(2610 11180);
DISPLAY 0.787234 (2610 11180);
PAINT MONO (2610 11180);
DISPLAY INVISIBLE (2610 11180);
FORCEPROP 1 LAST MATERIAL X7R
J 0
(2675 11275);
DISPLAY 0.510638 (2675 11275);
PAINT RED (2675 11275);
FORCEPROP 1 LAST PACK_TYPE C0402
J 0
(2675 11225);
DISPLAY 0.510638 (2675 11225);
FORCEPROP 1 LAST VOLTAGE 50V
J 0
(2675 11300);
DISPLAY 0.510638 (2675 11300);
FORCEPROP 0 LAST ROOM SCM_P12V_MPS_BOM2
J 0
(2600 11175);
DISPLAY 0.446809 (2600 11175);
PAINT RED (2600 11175);
FORCEPROP 1 LAST VALUE 100NF
J 0
(2675 11325);
DISPLAY 0.510638 (2675 11325);
FORCEPROP 2 LAST CDS_LIB pure_quanta
J 0
(2600 11300);
DISPLAY INVISIBLE (2600 11300);
FORCEPROP 1 LAST TOLERANCE 10%
J 0
(2650 11250);
DISPLAY 0.638298 (2650 11250);
DISPLAY INVISIBLE (2650 11250);
FORCEPROP 1 LAST PATH I45
J 0
(2650 11450);
DISPLAY 0.978723 (2650 11450);
PAINT WHITE (2650 11450);
DISPLAY INVISIBLE (2650 11450);
FORCEPROP 1 LAST PART_NUMBER CH4106K1B01
J 0
(2675 11250);
DISPLAY 0.510638 (2675 11250);
DISPLAY INVISIBLE (2675 11250);
FORCEADD GND..1
(3825 11300);
FORCEPROP 3 LASTPIN (3825 11350) SIG_NAME GND\g
J 0
(3835 11360);
DISPLAY 0.659574 (3835 11360);
PAINT MONO (3835 11360);
DISPLAY INVISIBLE (3835 11360);
FORCEPROP 2 LAST CDS_LIB pure_quanta_power
J 0
(3825 11300);
DISPLAY INVISIBLE (3825 11300);
FORCEPROP 1 LAST SIZE 1B
J 0
(3900 11250);
DISPLAY 0.872340 (3900 11250);
PAINT GREEN (3900 11250);
DISPLAY INVISIBLE (3900 11250);
FORCEPROP 1 LAST HDL_POWER GND
J 0
(3825 11450);
DISPLAY 0.872340 (3825 11450);
PAINT GREEN (3825 11450);
DISPLAY INVISIBLE (3825 11450);
FORCEPROP 1 LAST PATH I46
J 0
(3900 11300);
DISPLAY 0.872340 (3900 11300);
PAINT AQUA (3900 11300);
DISPLAY INVISIBLE (3900 11300);
FORCEADD OFFPAGE..1
R 2
(2825 11900);
PAINT AQUA (2825 11900);
FORCEPROP 2 LAST $XR0 152 
J 0
(3011 11900);
DISPLAY 0.638298 (3011 11900);
PAINT MONO (3011 11900);
FORCEPROP 2 LAST CDS_LIB standard
J 2
(2825 11900);
DISPLAY INVISIBLE (2825 11900);
FORCEPROP 1 LAST OFFPAGE TRUE
J 2
(2500 11775);
DISPLAY 0.872340 (2500 11775);
PAINT AQUA (2500 11775);
DISPLAY INVISIBLE (2500 11775);
FORCEPROP 1 LAST COMMENT_BODY TRUE
J 2
(2700 11800);
DISPLAY 0.872340 (2700 11800);
PAINT GREEN (2700 11800);
DISPLAY INVISIBLE (2700 11800);
FORCEPROP 2 LAST PATH I47
J 0
(3025 11950);
DISPLAY 0.680851 (3025 11950);
DISPLAY INVISIBLE (3025 11950);
FORCEADD VCCAUX15..1
(3475 11725);
FORCEPROP 3 LASTPIN (3475 11675) SIG_NAME P3V3_AUX\g
J 0
(3485 11685);
DISPLAY 0.659574 (3485 11685);
PAINT MONO (3485 11685);
DISPLAY INVISIBLE (3485 11685);
FORCEPROP 1 LAST HDL_POWER P3V3_AUX
J 1
(3475 11750);
DISPLAY 0.574468 (3475 11750);
PAINT GREEN (3475 11750);
FORCEPROP 2 LAST CDS_LIB pure_quanta_power
J 0
(3475 11725);
DISPLAY INVISIBLE (3475 11725);
FORCEPROP 1 LAST PATH I48
J 0
(3525 11750);
DISPLAY 0.872340 (3525 11750);
PAINT AQUA (3525 11750);
DISPLAY INVISIBLE (3525 11750);
FORCEADD Q_RES..2
(3625 11625);
FORCEPROP 1 LAST LOCATION PR4011
J 0
(3675 11700);
DISPLAY 0.638298 (3675 11700);
FORCEPROP 0 LAST $SEC 1
J 0
(3675 11800);
DISPLAY INVISIBLE (3675 11800);
FORCEPROP 0 LAST CDS_SEC 1
J 0
(3675 11800);
DISPLAY INVISIBLE (3675 11800);
FORCEPROP 1 LASTPIN (3625 11725) $PN 1
J 0
(3630 11687);
DISPLAY 0.787234 (3630 11687);
PAINT MONO (3630 11687);
DISPLAY INVISIBLE (3630 11687);
FORCEPROP 1 LASTPIN (3625 11525) $PN 2
J 0
(3630 11535);
DISPLAY 0.787234 (3630 11535);
PAINT MONO (3630 11535);
DISPLAY INVISIBLE (3630 11535);
FORCEPROP 1 LAST PACK_TYPE 0402LF
J 0
(3675 11550);
DISPLAY 0.510638 (3675 11550);
FORCEPROP 1 LAST MATERIAL CHIP
J 0
(3675 11600);
DISPLAY 0.510638 (3675 11600);
PAINT RED (3675 11600);
FORCEPROP 1 LAST TOLERANCE 1%
J 0
(3675 11650);
DISPLAY 0.510638 (3675 11650);
FORCEPROP 0 LAST ROOM SCM_P12V_MPS_BOM2
J 0
(3675 11750);
DISPLAY 0.446809 (3675 11750);
PAINT RED (3675 11750);
FORCEPROP 1 LAST VALUE 10K
J 0
(3675 11675);
DISPLAY 0.510638 (3675 11675);
FORCEPROP 1 LAST WATTAGE 1/16W
J 0
(3675 11625);
DISPLAY 0.510638 (3675 11625);
FORCEPROP 2 LAST CDS_LIB pure_quanta
J 0
(3625 11625);
DISPLAY INVISIBLE (3625 11625);
FORCEPROP 1 LAST PATH I49
J 0
(3675 11800);
DISPLAY 0.978723 (3675 11800);
PAINT WHITE (3675 11800);
DISPLAY INVISIBLE (3675 11800);
FORCEPROP 1 LAST PART_NUMBER CS31002FB08
J 0
(3675 11575);
DISPLAY 0.510638 (3675 11575);
DISPLAY INVISIBLE (3675 11575);
FORCEADD GND..1
(-75 11275);
FORCEPROP 3 LASTPIN (-75 11325) SIG_NAME GND\g
J 0
(-65 11335);
DISPLAY 0.659574 (-65 11335);
PAINT MONO (-65 11335);
DISPLAY INVISIBLE (-65 11335);
FORCEPROP 2 LAST CDS_LIB pure_quanta_power
J 0
(-75 11275);
DISPLAY INVISIBLE (-75 11275);
FORCEPROP 1 LAST SIZE 1B
J 0
(0 11225);
DISPLAY 0.872340 (0 11225);
PAINT GREEN (0 11225);
DISPLAY INVISIBLE (0 11225);
FORCEPROP 1 LAST HDL_POWER GND
J 0
(-75 11425);
DISPLAY 0.872340 (-75 11425);
PAINT GREEN (-75 11425);
DISPLAY INVISIBLE (-75 11425);
FORCEPROP 1 LAST PATH I5
J 0
(0 11275);
DISPLAY 0.872340 (0 11275);
PAINT AQUA (0 11275);
DISPLAY INVISIBLE (0 11275);
FORCEADD Q_RES..2
(3225 12125);
FORCEPROP 1 LAST LOCATION PR4009
J 0
(3275 12175);
DISPLAY 0.574468 (3275 12175);
FORCEPROP 0 LAST $SEC 1
J 0
(3250 12250);
DISPLAY 0.680851 (3250 12250);
PAINT MONO (3250 12250);
DISPLAY INVISIBLE (3250 12250);
FORCEPROP 0 LAST CDS_SEC 1
J 0
(3250 12250);
DISPLAY 1.021277 (3250 12250);
DISPLAY INVISIBLE (3250 12250);
FORCEPROP 1 LASTPIN (3225 12225) $PN 1
J 0
(3230 12187);
DISPLAY 0.787234 (3230 12187);
FORCEPROP 1 LASTPIN (3225 12025) $PN 2
J 0
(3230 12035);
DISPLAY 0.787234 (3230 12035);
FORCEPROP 1 LAST PACK_TYPE 0402LF
J 0
(3275 12050);
DISPLAY 0.468085 (3275 12050);
FORCEPROP 1 LAST TOLERANCE 1%
J 0
(3275 12125);
DISPLAY 0.468085 (3275 12125);
FORCEPROP 1 LAST MATERIAL EMPTY
J 0
(3275 12100);
DISPLAY 0.574468 (3275 12100);
PAINT RED (3275 12100);
FORCEPROP 1 LAST VALUE 71.5K
J 0
(3275 12150);
DISPLAY 0.468085 (3275 12150);
FORCEPROP 0 LAST ROOM SCM_P12V_MPS_BOM2
J 0
(3250 12250);
DISPLAY 0.446809 (3250 12250);
PAINT RED (3250 12250);
FORCEPROP 1 LAST WATTAGE 1/16W
J 0
(3250 12100);
DISPLAY 0.723404 (3250 12100);
PAINT SKYBLUE (3250 12100);
DISPLAY INVISIBLE (3250 12100);
FORCEPROP 2 LAST CDS_LIB pure_quanta
J 0
(3225 12125);
DISPLAY INVISIBLE (3225 12125);
FORCEPROP 1 LAST PATH I50
J 0
(3275 12300);
DISPLAY 0.978723 (3275 12300);
PAINT WHITE (3275 12300);
DISPLAY INVISIBLE (3275 12300);
FORCEPROP 1 LAST PART_NUMBER CS37152FB05
J 0
(3275 12075);
DISPLAY 0.468085 (3275 12075);
DISPLAY INVISIBLE (3275 12075);
FORCEADD Q_RES..2
(3625 12050);
FORCEPROP 1 LAST LOCATION PR4010
J 0
(3675 12100);
DISPLAY 0.510638 (3675 12100);
FORCEPROP 0 LAST $SEC 1
J 0
(3675 12225);
DISPLAY INVISIBLE (3675 12225);
FORCEPROP 0 LAST CDS_SEC 1
J 0
(3675 12225);
DISPLAY INVISIBLE (3675 12225);
FORCEPROP 1 LASTPIN (3625 12150) $PN 1
J 0
(3630 12112);
DISPLAY 0.787234 (3630 12112);
PAINT MONO (3630 12112);
DISPLAY INVISIBLE (3630 12112);
FORCEPROP 1 LASTPIN (3625 11950) $PN 2
J 0
(3630 11960);
DISPLAY 0.787234 (3630 11960);
PAINT MONO (3630 11960);
DISPLAY INVISIBLE (3630 11960);
FORCEPROP 0 LAST ROOM SCM_P12V_MPS_BOM2
J 0
(3675 12125);
DISPLAY 0.446809 (3675 12125);
PAINT RED (3675 12125);
FORCEPROP 1 LAST PACK_TYPE 0402LF
J 0
(3675 11950);
DISPLAY 0.510638 (3675 11950);
FORCEPROP 1 LAST MATERIAL CHIP
J 0
(3675 12000);
DISPLAY 0.510638 (3675 12000);
PAINT RED (3675 12000);
FORCEPROP 1 LAST WATTAGE 1/16W
J 0
(3675 12025);
DISPLAY 0.510638 (3675 12025);
FORCEPROP 1 LAST TOLERANCE 1%
J 0
(3675 12050);
DISPLAY 0.510638 (3675 12050);
FORCEPROP 1 LAST VALUE 120K
J 0
(3675 12075);
DISPLAY 0.510638 (3675 12075);
FORCEPROP 2 LAST CDS_LIB pure_quanta
J 0
(3625 12050);
DISPLAY INVISIBLE (3625 12050);
FORCEPROP 1 LAST PATH I51
J 0
(3675 12225);
DISPLAY 0.978723 (3675 12225);
PAINT WHITE (3675 12225);
DISPLAY INVISIBLE (3675 12225);
FORCEPROP 1 LAST PART_NUMBER CS41202FB05
J 0
(3675 11975);
DISPLAY 0.510638 (3675 11975);
DISPLAY INVISIBLE (3675 11975);
FORCEADD Q_CAP..1
(4150 11625);
FORCEPROP 1 LAST LOCATION PC2239
J 0
(4225 11675);
DISPLAY 0.638298 (4225 11675);
FORCEPROP 0 LAST $SEC 1
J 0
(4225 11775);
DISPLAY INVISIBLE (4225 11775);
FORCEPROP 0 LAST CDS_SEC 1
J 0
(4225 11775);
DISPLAY INVISIBLE (4225 11775);
FORCEPROP 1 LASTPIN (4150 11725) $PN 1
J 0
(4160 11705);
DISPLAY 0.787234 (4160 11705);
PAINT MONO (4160 11705);
DISPLAY INVISIBLE (4160 11705);
FORCEPROP 1 LASTPIN (4150 11525) $PN 2
J 0
(4160 11505);
DISPLAY 0.787234 (4160 11505);
PAINT MONO (4160 11505);
DISPLAY INVISIBLE (4160 11505);
FORCEPROP 1 LAST TOLERANCE 20%
J 0
(4225 11600);
DISPLAY 0.510638 (4225 11600);
FORCEPROP 1 LAST MATERIAL X7R
J 0
(4225 11575);
DISPLAY 0.510638 (4225 11575);
PAINT RED (4225 11575);
FORCEPROP 1 LAST VOLTAGE 16V
J 0
(4225 11625);
DISPLAY 0.510638 (4225 11625);
FORCEPROP 1 LAST VALUE 2.2UF
J 0
(4225 11650);
DISPLAY 0.510638 (4225 11650);
FORCEPROP 0 LAST ROOM SCM_P12V_MPS_BOM2
J 0
(4225 11500);
DISPLAY 0.446809 (4225 11500);
PAINT RED (4225 11500);
FORCEPROP 1 LAST PACK_TYPE C0603
J 0
(4225 11525);
DISPLAY 0.510638 (4225 11525);
FORCEPROP 2 LAST CDS_LIB pure_quanta
J 0
(4150 11625);
DISPLAY INVISIBLE (4150 11625);
FORCEPROP 1 LAST PATH I52
J 0
(4200 11775);
DISPLAY 0.978723 (4200 11775);
PAINT WHITE (4200 11775);
DISPLAY INVISIBLE (4200 11775);
FORCEPROP 1 LAST PART_NUMBER CH5223M1900
J 0
(4225 11550);
DISPLAY 0.510638 (4225 11550);
DISPLAY INVISIBLE (4225 11550);
FORCEADD Q_RES..2
(4150 12050);
FORCEPROP 1 LAST LOCATION PR4014
J 0
(4225 12100);
DISPLAY 0.510638 (4225 12100);
FORCEPROP 0 LAST $SEC 1
J 0
(4200 12225);
DISPLAY 0.680851 (4200 12225);
PAINT MONO (4200 12225);
DISPLAY INVISIBLE (4200 12225);
FORCEPROP 0 LAST CDS_SEC 1
J 0
(4200 12225);
DISPLAY 1.021277 (4200 12225);
DISPLAY INVISIBLE (4200 12225);
FORCEPROP 1 LASTPIN (4150 12150) $PN 1
J 0
(4155 12112);
DISPLAY 0.787234 (4155 12112);
PAINT MONO (4155 12112);
FORCEPROP 1 LASTPIN (4150 11950) $PN 2
J 0
(4155 11960);
DISPLAY 0.787234 (4155 11960);
PAINT MONO (4155 11960);
FORCEPROP 1 LAST PACK_TYPE 0603LF
J 0
(4225 11950);
DISPLAY 0.510638 (4225 11950);
FORCEPROP 1 LAST WATTAGE 1/10W
J 0
(4225 12025);
DISPLAY 0.510638 (4225 12025);
FORCEPROP 0 LAST ROOM SCM_P12V_MPS_BOM2
J 0
(4225 12125);
DISPLAY 0.446809 (4225 12125);
PAINT RED (4225 12125);
FORCEPROP 1 LAST VALUE 49.9
J 0
(4225 12075);
DISPLAY 0.510638 (4225 12075);
FORCEPROP 1 LAST MATERIAL CHIP
J 0
(4225 12000);
DISPLAY 0.510638 (4225 12000);
PAINT RED (4225 12000);
FORCEPROP 1 LAST TOLERANCE 1%
J 0
(4225 12050);
DISPLAY 0.510638 (4225 12050);
FORCEPROP 2 LAST CDS_LIB pure_quanta
J 0
(4150 12050);
DISPLAY INVISIBLE (4150 12050);
FORCEPROP 1 LAST PATH I53
J 0
(4200 12225);
DISPLAY 0.978723 (4200 12225);
PAINT WHITE (4200 12225);
DISPLAY INVISIBLE (4200 12225);
FORCEPROP 1 LAST PART_NUMBER CS04993F909
J 0
(4225 11975);
DISPLAY 0.510638 (4225 11975);
DISPLAY INVISIBLE (4225 11975);
FORCEADD UNIVERSAL_POWER..1
(4150 12350);
FORCEPROP 3 LASTPIN (4150 12300) SIG_NAME P12V_AUX\g
J 0
(4160 12310);
DISPLAY 0.659574 (4160 12310);
PAINT MONO (4160 12310);
DISPLAY INVISIBLE (4160 12310);
FORCEPROP 1 LAST HDL_POWER P12V_AUX
J 1
(4150 12400);
DISPLAY 0.702128 (4150 12400);
PAINT GREEN (4150 12400);
FORCEPROP 2 LAST CDS_LIB pure_quanta_power
J 0
(4150 12350);
DISPLAY INVISIBLE (4150 12350);
FORCEPROP 1 LAST PATH I54
J 0
(4200 12375);
DISPLAY 0.872340 (4200 12375);
PAINT AQUA (4200 12375);
DISPLAY INVISIBLE (4200 12375);
FORCEADD GND..1
(4500 12200);
FORCEPROP 3 LASTPIN (4500 12250) SIG_NAME GND\g
J 0
(4510 12260);
DISPLAY 0.659574 (4510 12260);
PAINT MONO (4510 12260);
DISPLAY INVISIBLE (4510 12260);
FORCEPROP 2 LAST CDS_LIB pure_quanta_power
J 0
(4500 12200);
DISPLAY INVISIBLE (4500 12200);
FORCEPROP 1 LAST SIZE 1B
J 0
(4575 12150);
DISPLAY 0.872340 (4575 12150);
PAINT GREEN (4575 12150);
DISPLAY INVISIBLE (4575 12150);
FORCEPROP 1 LAST HDL_POWER GND
J 0
(4500 12350);
DISPLAY 0.872340 (4500 12350);
PAINT GREEN (4500 12350);
DISPLAY INVISIBLE (4500 12350);
FORCEPROP 1 LAST PATH I55
J 0
(4575 12200);
DISPLAY 0.872340 (4575 12200);
PAINT AQUA (4575 12200);
DISPLAY INVISIBLE (4575 12200);
FORCEADD Q_CAP..1
R 2
(4500 12475);
FORCEPROP 1 LAST LOCATION PC2241
J 0
(4575 12525);
DISPLAY 0.638298 (4575 12525);
FORCEPROP 0 LAST $SEC 1
J 0
(4850 12625);
DISPLAY 0.680851 (4850 12625);
PAINT MONO (4850 12625);
DISPLAY INVISIBLE (4850 12625);
FORCEPROP 0 LAST CDS_SEC 1
J 0
(4850 12625);
DISPLAY 1.021277 (4850 12625);
DISPLAY INVISIBLE (4850 12625);
FORCEPROP 1 LASTPIN (4500 12575) $PN 1
J 2
(4490 12555);
DISPLAY 0.787234 (4490 12555);
PAINT MONO (4490 12555);
FORCEPROP 1 LASTPIN (4500 12375) $PN 2
J 2
(4490 12355);
DISPLAY 0.787234 (4490 12355);
PAINT MONO (4490 12355);
FORCEPROP 1 LAST VOLTAGE 25V
J 0
(4575 12475);
DISPLAY 0.510638 (4575 12475);
FORCEPROP 1 LAST TOLERANCE 10%
J 0
(4575 12450);
DISPLAY 0.510638 (4575 12450);
FORCEPROP 1 LAST MATERIAL X7R
J 0
(4575 12425);
DISPLAY 0.510638 (4575 12425);
PAINT RED (4575 12425);
FORCEPROP 1 LAST VALUE 0.1UF
J 0
(4575 12500);
DISPLAY 0.510638 (4575 12500);
FORCEPROP 1 LAST PACK_TYPE 0402
J 0
(4575 12375);
DISPLAY 0.510638 (4575 12375);
FORCEPROP 0 LAST ROOM SCM_P12V_MPS_BOM2
J 0
(4575 12575);
DISPLAY 0.553191 (4575 12575);
PAINT RED (4575 12575);
FORCEPROP 2 LAST CDS_LIB pure_quanta
J 0
(4500 12475);
DISPLAY INVISIBLE (4500 12475);
FORCEPROP 1 LAST PATH I56
J 2
(4450 12625);
DISPLAY 0.978723 (4450 12625);
PAINT WHITE (4450 12625);
DISPLAY INVISIBLE (4450 12625);
FORCEPROP 1 LAST PART_NUMBER CH4104K1B00
J 0
(4575 12400);
DISPLAY 0.510638 (4575 12400);
DISPLAY INVISIBLE (4575 12400);
FORCEADD UNIVERSAL_POWER..1
R 2
(4500 12750);
FORCEPROP 3 LASTPIN (4500 12700) SIG_NAME P12V_SCM_R\g
J 0
(4510 12710);
DISPLAY 0.659574 (4510 12710);
PAINT MONO (4510 12710);
DISPLAY INVISIBLE (4510 12710);
FORCEPROP 1 LAST HDL_POWER P12V_SCM_R
J 1
(4500 12800);
DISPLAY 0.723404 (4500 12800);
PAINT GREEN (4500 12800);
FORCEPROP 2 LAST CDS_LIB pure_quanta_power
J 0
(4500 12750);
DISPLAY INVISIBLE (4500 12750);
FORCEPROP 1 LAST PATH I57
J 2
(4450 12775);
DISPLAY 0.872340 (4450 12775);
PAINT AQUA (4450 12775);
DISPLAY INVISIBLE (4450 12775);
FORCEADD OFFPAGE..2
(4800 11775);
PAINT AQUA (4800 11775);
FORCEPROP 2 LAST $XR0 152 
J 0
(4989 11775);
DISPLAY 0.638298 (4989 11775);
PAINT MONO (4989 11775);
FORCEPROP 2 LAST CDS_LIB standard
J 0
(4800 11775);
DISPLAY INVISIBLE (4800 11775);
FORCEPROP 1 LAST OFFPAGE TRUE
J 0
(5125 11650);
DISPLAY 0.872340 (5125 11650);
PAINT AQUA (5125 11650);
DISPLAY INVISIBLE (5125 11650);
FORCEPROP 1 LAST COMMENT_BODY TRUE
J 0
(4755 11680);
DISPLAY 0.872340 (4755 11680);
PAINT GREEN (4755 11680);
DISPLAY INVISIBLE (4755 11680);
FORCEPROP 2 LAST PATH I58
J 0
(5000 11825);
DISPLAY 0.680851 (5000 11825);
DISPLAY INVISIBLE (5000 11825);
FORCEADD GND..1
(675 14150);
FORCEPROP 3 LASTPIN (675 14200) SIG_NAME GND\g
J 0
(685 14210);
DISPLAY 0.659574 (685 14210);
PAINT MONO (685 14210);
DISPLAY INVISIBLE (685 14210);
FORCEPROP 1 LAST SIZE 1B
J 0
(750 14100);
DISPLAY 0.872340 (750 14100);
PAINT GREEN (750 14100);
DISPLAY INVISIBLE (750 14100);
FORCEPROP 2 LAST CDS_LIB pure_quanta_power
J 0
(675 14150);
DISPLAY INVISIBLE (675 14150);
FORCEPROP 1 LAST HDL_POWER GND
J 0
(675 14300);
DISPLAY 0.872340 (675 14300);
PAINT GREEN (675 14300);
DISPLAY INVISIBLE (675 14300);
FORCEPROP 1 LAST PATH I59
J 0
(750 14150);
DISPLAY 0.872340 (750 14150);
PAINT AQUA (750 14150);
DISPLAY INVISIBLE (750 14150);
FORCEADD Q_CAP..1
(350 11250);
FORCEPROP 1 LAST LOCATION PC2340
J 0
(400 11300);
DISPLAY 0.638298 (400 11300);
FORCEPROP 0 LAST $SEC 1
J 0
(400 11350);
DISPLAY 0.680851 (400 11350);
PAINT MONO (400 11350);
DISPLAY INVISIBLE (400 11350);
FORCEPROP 0 LAST CDS_SEC 1
J 0
(400 11350);
DISPLAY 1.021277 (400 11350);
DISPLAY INVISIBLE (400 11350);
FORCEPROP 1 LASTPIN (350 11350) $PN 1
J 0
(360 11330);
DISPLAY 0.787234 (360 11330);
PAINT MONO (360 11330);
FORCEPROP 1 LASTPIN (350 11150) $PN 2
J 0
(360 11130);
DISPLAY 0.787234 (360 11130);
PAINT MONO (360 11130);
FORCEPROP 1 LAST PACK_TYPE C0402
J 0
(400 11175);
DISPLAY 0.510638 (400 11175);
FORCEPROP 1 LAST VALUE 560PF
J 0
(400 11275);
DISPLAY 0.510638 (400 11275);
FORCEPROP 1 LAST VOLTAGE 50V
J 0
(400 11250);
DISPLAY 0.510638 (400 11250);
FORCEPROP 1 LAST MATERIAL X7R
J 0
(400 11225);
DISPLAY 0.510638 (400 11225);
PAINT RED (400 11225);
FORCEPROP 0 LAST ROOM SCM_P12V_MPS_BOM2
J 0
(425 11150);
DISPLAY 0.446809 (425 11150);
PAINT RED (425 11150);
FORCEPROP 2 LAST CDS_LIB pure_quanta
J 0
(350 11250);
DISPLAY INVISIBLE (350 11250);
FORCEPROP 1 LAST TOLERANCE 10%
J 0
(400 11200);
DISPLAY 0.638298 (400 11200);
DISPLAY INVISIBLE (400 11200);
FORCEPROP 1 LAST PATH I6
J 0
(400 11400);
DISPLAY 0.978723 (400 11400);
PAINT WHITE (400 11400);
DISPLAY INVISIBLE (400 11400);
FORCEPROP 1 LAST PART_NUMBER CH1566K1B09
J 0
(400 11200);
DISPLAY 0.510638 (400 11200);
DISPLAY INVISIBLE (400 11200);
FORCEADD Q_RES..2
(675 14375);
FORCEPROP 1 LAST LOCATION PR4002
J 0
(725 14450);
DISPLAY 0.638298 (725 14450);
FORCEPROP 0 LAST $SEC 1
J 0
(725 14500);
DISPLAY 0.680851 (725 14500);
PAINT MONO (725 14500);
DISPLAY INVISIBLE (725 14500);
FORCEPROP 0 LAST CDS_SEC 1
J 0
(725 14500);
DISPLAY 1.021277 (725 14500);
DISPLAY INVISIBLE (725 14500);
FORCEPROP 1 LASTPIN (675 14475) $PN 1
J 0
(680 14437);
DISPLAY 0.787234 (680 14437);
PAINT MONO (680 14437);
FORCEPROP 1 LASTPIN (675 14275) $PN 2
J 0
(680 14285);
DISPLAY 0.787234 (680 14285);
PAINT MONO (680 14285);
FORCEPROP 0 LAST ROOM SCM_P12V_MAM_BOM1
J 0
(725 14275);
DISPLAY 0.446809 (725 14275);
PAINT RED (725 14275);
FORCEPROP 1 LAST TOLERANCE 1%
J 0
(725 14400);
DISPLAY 0.404255 (725 14400);
FORCEPROP 1 LAST VALUE 15K
J 0
(725 14425);
DISPLAY 0.404255 (725 14425);
FORCEPROP 1 LAST MATERIAL CHIP
J 0
(725 14350);
DISPLAY 0.404255 (725 14350);
FORCEPROP 1 LAST PACK_TYPE 0402LF
J 0
(725 14300);
DISPLAY 0.404255 (725 14300);
FORCEPROP 1 LAST WATTAGE 1/16W
J 0
(725 14375);
DISPLAY 0.404255 (725 14375);
FORCEPROP 2 LAST CDS_LIB pure_quanta
J 0
(675 14375);
DISPLAY INVISIBLE (675 14375);
FORCEPROP 1 LAST PATH I60
J 0
(725 14550);
DISPLAY 0.978723 (725 14550);
PAINT WHITE (725 14550);
DISPLAY INVISIBLE (725 14550);
FORCEPROP 1 LAST PART_NUMBER CS31502FB05
J 0
(725 14325);
DISPLAY 0.404255 (725 14325);
DISPLAY INVISIBLE (725 14325);
FORCEADD GND..1
(1525 14150);
FORCEPROP 3 LASTPIN (1525 14200) SIG_NAME GND\g
J 0
(1535 14210);
DISPLAY 0.659574 (1535 14210);
PAINT MONO (1535 14210);
DISPLAY INVISIBLE (1535 14210);
FORCEPROP 2 LAST CDS_LIB pure_quanta_power
J 0
(1525 14150);
DISPLAY INVISIBLE (1525 14150);
FORCEPROP 1 LAST SIZE 1B
J 0
(1600 14100);
DISPLAY 0.872340 (1600 14100);
PAINT GREEN (1600 14100);
DISPLAY INVISIBLE (1600 14100);
FORCEPROP 1 LAST HDL_POWER GND
J 0
(1525 14300);
DISPLAY 0.872340 (1525 14300);
PAINT GREEN (1525 14300);
DISPLAY INVISIBLE (1525 14300);
FORCEPROP 1 LAST PATH I61
J 0
(1600 14150);
DISPLAY 0.872340 (1600 14150);
PAINT AQUA (1600 14150);
DISPLAY INVISIBLE (1600 14150);
FORCEADD Q_RES..2
(1525 14375);
FORCEPROP 1 LAST LOCATION PR4004
J 0
(1575 14425);
DISPLAY 0.638298 (1575 14425);
FORCEPROP 0 LAST $SEC 1
J 0
(1575 14525);
DISPLAY 0.680851 (1575 14525);
PAINT MONO (1575 14525);
DISPLAY INVISIBLE (1575 14525);
FORCEPROP 0 LAST CDS_SEC 1
J 0
(1575 14500);
DISPLAY INVISIBLE (1575 14500);
FORCEPROP 1 LASTPIN (1525 14475) $PN 1
J 0
(1530 14437);
DISPLAY 0.787234 (1530 14437);
PAINT MONO (1530 14437);
FORCEPROP 1 LASTPIN (1525 14275) $PN 2
J 0
(1530 14285);
DISPLAY 0.787234 (1530 14285);
PAINT MONO (1530 14285);
FORCEPROP 0 LAST ROOM SCM_P12V_MAM_BOM1
J 0
(1475 14475);
DISPLAY 0.361702 (1475 14475);
PAINT RED (1475 14475);
FORCEPROP 1 LAST TOLERANCE 1%
J 0
(1575 14375);
DISPLAY 0.510638 (1575 14375);
FORCEPROP 1 LAST MATERIAL CHIP
J 0
(1575 14325);
DISPLAY 0.510638 (1575 14325);
FORCEPROP 1 LAST VALUE 17.8K
J 0
(1575 14400);
DISPLAY 0.510638 (1575 14400);
FORCEPROP 1 LAST PACK_TYPE 0402LF
J 0
(1575 14275);
DISPLAY 0.510638 (1575 14275);
FORCEPROP 1 LAST WATTAGE 1/16W
J 0
(1575 14350);
DISPLAY 0.510638 (1575 14350);
FORCEPROP 2 LAST CDS_LIB pure_quanta
J 0
(1525 14375);
DISPLAY INVISIBLE (1525 14375);
FORCEPROP 1 LAST PATH I62
J 0
(1575 14550);
DISPLAY 0.978723 (1575 14550);
PAINT WHITE (1575 14550);
DISPLAY INVISIBLE (1575 14550);
FORCEPROP 1 LAST PART_NUMBER CS31782FB04
J 0
(1575 14300);
DISPLAY 0.510638 (1575 14300);
DISPLAY INVISIBLE (1575 14300);
FORCEADD Q_RES..2
(675 14650);
FORCEPROP 1 LAST LOCATION PR4001
J 0
(725 14725);
DISPLAY 0.638298 (725 14725);
FORCEPROP 0 LAST $SEC 1
J 0
(725 14775);
DISPLAY 0.680851 (725 14775);
PAINT MONO (725 14775);
DISPLAY INVISIBLE (725 14775);
FORCEPROP 0 LAST CDS_SEC 1
J 0
(725 14775);
DISPLAY 1.021277 (725 14775);
DISPLAY INVISIBLE (725 14775);
FORCEPROP 1 LASTPIN (675 14750) $PN 1
J 0
(680 14712);
DISPLAY 0.787234 (680 14712);
PAINT MONO (680 14712);
FORCEPROP 1 LASTPIN (675 14550) $PN 2
J 0
(680 14560);
DISPLAY 0.787234 (680 14560);
PAINT MONO (680 14560);
FORCEPROP 1 LAST WATTAGE 1/16W
J 0
(725 14650);
DISPLAY 0.404255 (725 14650);
FORCEPROP 1 LAST MATERIAL CHIP
J 0
(725 14625);
DISPLAY 0.404255 (725 14625);
FORCEPROP 1 LAST TOLERANCE 1%
J 0
(725 14675);
DISPLAY 0.404255 (725 14675);
FORCEPROP 1 LAST VALUE 6.8K
J 0
(725 14700);
DISPLAY 0.404255 (725 14700);
FORCEPROP 1 LAST PACK_TYPE 0402LF
J 0
(725 14575);
DISPLAY 0.404255 (725 14575);
FORCEPROP 0 LAST ROOM SCM_P12V_MAM_BOM1
J 0
(725 14550);
DISPLAY 0.446809 (725 14550);
PAINT RED (725 14550);
FORCEPROP 2 LAST CDS_LIB pure_quanta
J 0
(675 14650);
DISPLAY INVISIBLE (675 14650);
FORCEPROP 1 LAST PATH I63
J 0
(725 14825);
DISPLAY 0.978723 (725 14825);
PAINT WHITE (725 14825);
DISPLAY INVISIBLE (725 14825);
FORCEPROP 1 LAST PART_NUMBER CS26802FB02
J 0
(725 14600);
DISPLAY 0.404255 (725 14600);
DISPLAY INVISIBLE (725 14600);
FORCEADD GND..1
(1000 14825);
FORCEPROP 3 LASTPIN (1000 14875) SIG_NAME GND\g
J 0
(1010 14885);
DISPLAY 0.659574 (1010 14885);
PAINT MONO (1010 14885);
DISPLAY INVISIBLE (1010 14885);
FORCEPROP 2 LAST CDS_LIB pure_quanta_power
J 0
(1000 14825);
DISPLAY INVISIBLE (1000 14825);
FORCEPROP 1 LAST SIZE 1B
J 0
(1075 14775);
DISPLAY 0.872340 (1075 14775);
PAINT GREEN (1075 14775);
DISPLAY INVISIBLE (1075 14775);
FORCEPROP 1 LAST HDL_POWER GND
J 0
(1000 14975);
DISPLAY 0.872340 (1000 14975);
PAINT GREEN (1000 14975);
DISPLAY INVISIBLE (1000 14975);
FORCEPROP 1 LAST PATH I64
J 0
(1075 14825);
DISPLAY 0.872340 (1075 14825);
PAINT AQUA (1075 14825);
DISPLAY INVISIBLE (1075 14825);
FORCEADD Q_RES..2
(675 15325);
FORCEPROP 1 LAST LOCATION PR4000
J 0
(725 15400);
DISPLAY 0.638298 (725 15400);
FORCEPROP 0 LAST $SEC 1
J 0
(725 15450);
DISPLAY 0.680851 (725 15450);
PAINT MONO (725 15450);
DISPLAY INVISIBLE (725 15450);
FORCEPROP 0 LAST CDS_SEC 1
J 0
(725 15450);
DISPLAY 1.021277 (725 15450);
DISPLAY INVISIBLE (725 15450);
FORCEPROP 1 LASTPIN (675 15425) $PN 1
J 0
(680 15387);
DISPLAY 0.787234 (680 15387);
PAINT MONO (680 15387);
FORCEPROP 1 LASTPIN (675 15225) $PN 2
J 0
(680 15235);
DISPLAY 0.787234 (680 15235);
PAINT MONO (680 15235);
FORCEPROP 1 LAST PACK_TYPE 0402LF
J 0
(725 15250);
DISPLAY 0.404255 (725 15250);
FORCEPROP 1 LAST MATERIAL CHIP
J 0
(725 15300);
DISPLAY 0.404255 (725 15300);
FORCEPROP 1 LAST TOLERANCE 1%
J 0
(725 15350);
DISPLAY 0.404255 (725 15350);
FORCEPROP 1 LAST VALUE 160K
J 0
(725 15375);
DISPLAY 0.404255 (725 15375);
FORCEPROP 0 LAST ROOM SCM_P12V_MAM_BOM1
J 0
(600 15450);
DISPLAY 0.446809 (600 15450);
PAINT RED (600 15450);
FORCEPROP 1 LAST WATTAGE 1/16W
J 0
(725 15325);
DISPLAY 0.404255 (725 15325);
FORCEPROP 2 LAST CDS_LIB pure_quanta
J 0
(675 15325);
DISPLAY INVISIBLE (675 15325);
FORCEPROP 1 LAST PATH I65
J 0
(725 15500);
DISPLAY 0.978723 (725 15500);
PAINT WHITE (725 15500);
DISPLAY INVISIBLE (725 15500);
FORCEPROP 1 LAST PART_NUMBER CS41602FB05
J 0
(725 15275);
DISPLAY 0.404255 (725 15275);
DISPLAY INVISIBLE (725 15275);
FORCEADD Q_CAP..1
(1000 15200);
FORCEPROP 1 LAST LOCATION PC2233
J 0
(1050 15225);
DISPLAY 0.638298 (1050 15225);
FORCEPROP 0 LAST $SEC 1
J 0
(1050 15275);
DISPLAY 0.680851 (1050 15275);
PAINT MONO (1050 15275);
DISPLAY INVISIBLE (1050 15275);
FORCEPROP 0 LAST CDS_SEC 1
J 0
(1050 15275);
DISPLAY 1.021277 (1050 15275);
DISPLAY INVISIBLE (1050 15275);
FORCEPROP 1 LASTPIN (1000 15300) $PN 1
J 0
(1010 15280);
DISPLAY 0.787234 (1010 15280);
PAINT MONO (1010 15280);
FORCEPROP 1 LASTPIN (1000 15100) $PN 2
J 0
(1010 15080);
DISPLAY 0.787234 (1010 15080);
PAINT MONO (1010 15080);
FORCEPROP 0 LAST ROOM SCM_P12V_MAM_BOM1
J 0
(1050 15275);
DISPLAY 0.446809 (1050 15275);
PAINT RED (1050 15275);
FORCEPROP 1 LAST MATERIAL X6S
J 0
(1050 15175);
DISPLAY 0.510638 (1050 15175);
FORCEPROP 1 LAST VALUE 1UF
J 0
(1050 15200);
DISPLAY 0.510638 (1050 15200);
FORCEPROP 1 LAST VOLTAGE 25V
J 0
(1050 15150);
DISPLAY 0.510638 (1050 15150);
FORCEPROP 1 LAST PACK_TYPE C0402
J 0
(1050 15125);
DISPLAY 0.510638 (1050 15125);
FORCEPROP 1 LAST TOLERANCE 10%
J 0
(1050 15150);
DISPLAY 0.638298 (1050 15150);
DISPLAY INVISIBLE (1050 15150);
FORCEPROP 2 LAST CDS_LIB pure_quanta
J 0
(1000 15200);
DISPLAY INVISIBLE (1000 15200);
FORCEPROP 1 LAST PATH I66
J 0
(1050 15350);
DISPLAY 0.978723 (1050 15350);
PAINT WHITE (1050 15350);
DISPLAY INVISIBLE (1050 15350);
FORCEPROP 1 LAST PART_NUMBER CH5104KEB02
J 0
(1050 15100);
DISPLAY 0.510638 (1050 15100);
DISPLAY INVISIBLE (1050 15100);
FORCEADD Q_CAP..1
R 1
(1225 14900);
FORCEPROP 1 LAST LOCATION PC2234
J 0
(1050 14950);
DISPLAY 0.638298 (1050 14950);
FORCEPROP 0 LAST $SEC 1
R 1
J 0
(1050 15000);
DISPLAY 0.680851 (1050 15000);
PAINT MONO (1050 15000);
DISPLAY INVISIBLE (1050 15000);
FORCEPROP 0 LAST CDS_SEC 1
R 1
J 0
(1050 15000);
DISPLAY 1.021277 (1050 15000);
DISPLAY INVISIBLE (1050 15000);
FORCEPROP 1 LASTPIN (1125 14900) $PN 1
R 1
J 0
(1145 14910);
DISPLAY 0.787234 (1145 14910);
PAINT MONO (1145 14910);
FORCEPROP 1 LASTPIN (1325 14900) $PN 2
R 1
J 0
(1345 14910);
DISPLAY 0.787234 (1345 14910);
PAINT MONO (1345 14910);
FORCEPROP 1 LAST VOLTAGE 25V
J 0
(1375 14950);
DISPLAY 0.510638 (1375 14950);
FORCEPROP 1 LAST VALUE 1UF
J 0
(1200 14950);
DISPLAY 0.510638 (1200 14950);
FORCEPROP 1 LAST PACK_TYPE C0402
J 0
(1050 14850);
DISPLAY 0.510638 (1050 14850);
FORCEPROP 0 LAST ROOM SCM_P12V_MAM_BOM1
J 0
(950 15000);
DISPLAY 0.446809 (950 15000);
PAINT RED (950 15000);
FORCEPROP 2 LAST CDS_LIB pure_quanta
J 0
(1225 14900);
DISPLAY INVISIBLE (1225 14900);
FORCEPROP 1 LAST MATERIAL X6S
R 1
J 0
(1225 14950);
DISPLAY 0.638298 (1225 14950);
DISPLAY INVISIBLE (1225 14950);
FORCEPROP 1 LAST TOLERANCE 10%
R 1
J 0
(1275 14950);
DISPLAY 0.638298 (1275 14950);
DISPLAY INVISIBLE (1275 14950);
FORCEPROP 1 LAST PATH I67
R 1
J 0
(1075 14950);
DISPLAY 0.978723 (1075 14950);
PAINT WHITE (1075 14950);
DISPLAY INVISIBLE (1075 14950);
FORCEPROP 1 LAST PART_NUMBER CH5104KEB02
J 0
(1275 14850);
DISPLAY 0.510638 (1275 14850);
DISPLAY INVISIBLE (1275 14850);
FORCEADD Q_RES..2
(1000 15625);
FORCEPROP 1 LAST LOCATION PR4003
J 0
(1050 15700);
DISPLAY 0.638298 (1050 15700);
FORCEPROP 0 LAST $SEC 1
J 0
(1050 15750);
DISPLAY 0.680851 (1050 15750);
PAINT MONO (1050 15750);
DISPLAY INVISIBLE (1050 15750);
FORCEPROP 0 LAST CDS_SEC 1
J 0
(1050 15750);
DISPLAY 1.021277 (1050 15750);
DISPLAY INVISIBLE (1050 15750);
FORCEPROP 1 LASTPIN (1000 15725) $PN 1
J 0
(1005 15687);
DISPLAY 0.787234 (1005 15687);
PAINT MONO (1005 15687);
FORCEPROP 1 LASTPIN (1000 15525) $PN 2
J 0
(1005 15535);
DISPLAY 0.787234 (1005 15535);
PAINT MONO (1005 15535);
FORCEPROP 1 LAST PACK_TYPE 0402LF
J 0
(1050 15550);
DISPLAY 0.404255 (1050 15550);
FORCEPROP 0 LAST ROOM SCM_P12V_MAM_BOM1
J 0
(1050 15750);
DISPLAY 0.553191 (1050 15750);
PAINT RED (1050 15750);
FORCEPROP 1 LAST VALUE 10
J 0
(1050 15675);
DISPLAY 0.404255 (1050 15675);
FORCEPROP 1 LAST TOLERANCE 1%
J 0
(1050 15650);
DISPLAY 0.404255 (1050 15650);
FORCEPROP 1 LAST WATTAGE 1/16W
J 0
(1050 15625);
DISPLAY 0.404255 (1050 15625);
FORCEPROP 1 LAST MATERIAL CHIP
J 0
(1050 15600);
DISPLAY 0.404255 (1050 15600);
FORCEPROP 2 LAST CDS_LIB pure_quanta
J 0
(1000 15625);
DISPLAY INVISIBLE (1000 15625);
FORCEPROP 1 LAST PATH I68
J 0
(1050 15800);
DISPLAY 0.978723 (1050 15800);
PAINT WHITE (1050 15800);
DISPLAY INVISIBLE (1050 15800);
FORCEPROP 1 LAST PART_NUMBER CS01002FB07
J 0
(1050 15575);
DISPLAY 0.404255 (1050 15575);
DISPLAY INVISIBLE (1050 15575);
FORCEADD GND..1
(3000 14150);
FORCEPROP 3 LASTPIN (3000 14200) SIG_NAME GND\g
J 0
(3010 14210);
DISPLAY 0.659574 (3010 14210);
PAINT MONO (3010 14210);
DISPLAY INVISIBLE (3010 14210);
FORCEPROP 1 LAST SIZE 1B
J 0
(3075 14100);
DISPLAY 0.872340 (3075 14100);
PAINT GREEN (3075 14100);
DISPLAY INVISIBLE (3075 14100);
FORCEPROP 2 LAST CDS_LIB pure_quanta_power
J 0
(3000 14150);
DISPLAY INVISIBLE (3000 14150);
FORCEPROP 1 LAST HDL_POWER GND
J 0
(3000 14300);
DISPLAY 0.872340 (3000 14300);
PAINT GREEN (3000 14300);
DISPLAY INVISIBLE (3000 14300);
FORCEPROP 1 LAST PATH I69
J 0
(3075 14150);
DISPLAY 0.872340 (3075 14150);
PAINT AQUA (3075 14150);
DISPLAY INVISIBLE (3075 14150);
FORCEADD GND..1
(350 11025);
FORCEPROP 3 LASTPIN (350 11075) SIG_NAME GND\g
J 0
(360 11085);
DISPLAY 0.659574 (360 11085);
PAINT MONO (360 11085);
DISPLAY INVISIBLE (360 11085);
FORCEPROP 2 LAST CDS_LIB pure_quanta_power
J 0
(350 11025);
DISPLAY INVISIBLE (350 11025);
FORCEPROP 1 LAST SIZE 1B
J 0
(425 10975);
DISPLAY 0.872340 (425 10975);
PAINT GREEN (425 10975);
DISPLAY INVISIBLE (425 10975);
FORCEPROP 1 LAST HDL_POWER GND
J 0
(350 11175);
DISPLAY 0.872340 (350 11175);
PAINT GREEN (350 11175);
DISPLAY INVISIBLE (350 11175);
FORCEPROP 1 LAST PATH I7
J 0
(425 11025);
DISPLAY 0.872340 (425 11025);
PAINT AQUA (425 11025);
DISPLAY INVISIBLE (425 11025);
FORCEADD Q_RES..2
(3125 14525);
FORCEPROP 1 LAST LOCATION PR4008
J 0
(3175 14575);
DISPLAY 0.638298 (3175 14575);
FORCEPROP 0 LAST $SEC 1
J 0
(3175 14700);
DISPLAY 0.680851 (3175 14700);
PAINT MONO (3175 14700);
DISPLAY INVISIBLE (3175 14700);
FORCEPROP 0 LAST CDS_SEC 1
J 0
(3175 14700);
DISPLAY 1.021277 (3175 14700);
DISPLAY INVISIBLE (3175 14700);
FORCEPROP 1 LASTPIN (3125 14625) $PN 1
J 0
(3130 14587);
DISPLAY 0.787234 (3130 14587);
PAINT MONO (3130 14587);
FORCEPROP 1 LASTPIN (3125 14425) $PN 2
J 0
(3130 14435);
DISPLAY 0.787234 (3130 14435);
PAINT MONO (3130 14435);
FORCEPROP 1 LAST WATTAGE 1/16W
J 0
(3175 14500);
DISPLAY 0.404255 (3175 14500);
FORCEPROP 1 LAST VALUE 1.33K
J 0
(3175 14550);
DISPLAY 0.404255 (3175 14550);
FORCEPROP 1 LAST TOLERANCE 1%
J 0
(3175 14525);
DISPLAY 0.404255 (3175 14525);
FORCEPROP 1 LAST MATERIAL CHIP
J 0
(3175 14475);
DISPLAY 0.404255 (3175 14475);
FORCEPROP 1 LAST PACK_TYPE 0402LF
J 0
(3175 14425);
DISPLAY 0.404255 (3175 14425);
FORCEPROP 0 LAST ROOM SCM_P12V_MAM_BOM1
J 0
(3175 14625);
DISPLAY 0.553191 (3175 14625);
PAINT RED (3175 14625);
FORCEPROP 2 LAST CDS_LIB pure_quanta
J 0
(3125 14525);
DISPLAY INVISIBLE (3125 14525);
FORCEPROP 1 LAST PATH I70
J 0
(3175 14700);
DISPLAY 0.978723 (3175 14700);
PAINT WHITE (3175 14700);
DISPLAY INVISIBLE (3175 14700);
FORCEPROP 1 LAST PART_NUMBER CS21332FB05
J 0
(3175 14450);
DISPLAY 0.404255 (3175 14450);
DISPLAY INVISIBLE (3175 14450);
FORCEADD Q_CAP..1
(3075 15225);
FORCEPROP 1 LAST LOCATION PC2236
J 0
(3125 15275);
DISPLAY 0.808511 (3125 15275);
FORCEPROP 0 LAST $SEC 1
J 0
(3125 15375);
DISPLAY 0.680851 (3125 15375);
PAINT MONO (3125 15375);
DISPLAY INVISIBLE (3125 15375);
FORCEPROP 0 LAST CDS_SEC 1
J 0
(3125 15375);
DISPLAY 1.021277 (3125 15375);
DISPLAY INVISIBLE (3125 15375);
FORCEPROP 1 LASTPIN (3075 15325) $PN 1
J 0
(3085 15305);
DISPLAY 0.787234 (3085 15305);
PAINT MONO (3085 15305);
FORCEPROP 1 LASTPIN (3075 15125) $PN 2
J 0
(3085 15105);
DISPLAY 0.787234 (3085 15105);
PAINT MONO (3085 15105);
FORCEPROP 1 LAST VOLTAGE 50V
J 0
(3125 15225);
DISPLAY 0.510638 (3125 15225);
FORCEPROP 0 LAST ROOM SCM_P12V_MAM_BOM1
J 0
(3100 15350);
DISPLAY 0.361702 (3100 15350);
PAINT RED (3100 15350);
FORCEPROP 1 LAST VALUE 0.01UF
J 0
(3125 15250);
DISPLAY 0.510638 (3125 15250);
FORCEPROP 1 LAST PACK_TYPE C0402
J 0
(3125 15150);
DISPLAY 0.510638 (3125 15150);
FORCEPROP 1 LAST MATERIAL EMPTY
J 0
(3125 15200);
DISPLAY 0.510638 (3125 15200);
PAINT RED (3125 15200);
FORCEPROP 1 LAST TOLERANCE 10%
J 0
(3125 15175);
DISPLAY 0.638298 (3125 15175);
DISPLAY INVISIBLE (3125 15175);
FORCEPROP 2 LAST CDS_LIB pure_quanta
J 0
(3075 15225);
DISPLAY INVISIBLE (3075 15225);
FORCEPROP 1 LAST PATH I71
J 0
(3125 15375);
DISPLAY 0.978723 (3125 15375);
PAINT WHITE (3125 15375);
DISPLAY INVISIBLE (3125 15375);
FORCEPROP 1 LAST PART_NUMBER CH31006KB18
J 0
(3125 15175);
DISPLAY 0.510638 (3125 15175);
DISPLAY INVISIBLE (3125 15175);
FORCEADD Q_CAP..1
R 1
(3675 15000);
FORCEPROP 1 LAST LOCATION PC2237
J 0
(3400 15000);
DISPLAY 0.510638 (3400 15000);
FORCEPROP 0 LAST $SEC 1
R 1
J 0
(3775 15125);
DISPLAY 0.553191 (3775 15125);
PAINT MONO (3775 15125);
DISPLAY INVISIBLE (3775 15125);
FORCEPROP 0 LAST CDS_SEC 1
R 1
J 0
(3775 15125);
DISPLAY 1.021277 (3775 15125);
DISPLAY INVISIBLE (3775 15125);
FORCEPROP 1 LASTPIN (3575 15000) $PN 1
R 1
J 0
(3595 15010);
DISPLAY 0.787234 (3595 15010);
PAINT MONO (3595 15010);
FORCEPROP 1 LASTPIN (3775 15000) $PN 2
R 1
J 0
(3795 15010);
DISPLAY 0.787234 (3795 15010);
PAINT MONO (3795 15010);
FORCEPROP 1 LAST VOLTAGE 50V
J 0
(3775 15050);
DISPLAY 0.404255 (3775 15050);
FORCEPROP 1 LAST VALUE 3900PF
J 0
(3575 15050);
DISPLAY 0.404255 (3575 15050);
FORCEPROP 1 LAST PACK_TYPE C0402
J 0
(3450 14975);
DISPLAY 0.510638 (3450 14975);
FORCEPROP 0 LAST ROOM SCM_P12V_MAM_BOM1
J 0
(3525 15075);
DISPLAY 0.446809 (3525 15075);
PAINT RED (3525 15075);
FORCEPROP 2 LAST CDS_LIB pure_quanta
R 1
J 0
(3675 15000);
DISPLAY INVISIBLE (3675 15000);
FORCEPROP 1 LAST MATERIAL X7R
R 1
J 0
(3675 15050);
DISPLAY 0.638298 (3675 15050);
DISPLAY INVISIBLE (3675 15050);
FORCEPROP 1 LAST TOLERANCE 10%
R 1
J 0
(3725 15050);
DISPLAY 0.638298 (3725 15050);
DISPLAY INVISIBLE (3725 15050);
FORCEPROP 1 LAST PATH I72
R 1
J 0
(3525 15050);
DISPLAY 0.978723 (3525 15050);
PAINT WHITE (3525 15050);
DISPLAY INVISIBLE (3525 15050);
FORCEPROP 1 LAST PART_NUMBER CH23906KB14
J 0
(3800 15025);
DISPLAY 0.404255 (3800 15025);
DISPLAY INVISIBLE (3800 15025);
FORCEADD Q_RES..1
(3750 14900);
FORCEPROP 1 LAST LOCATION PR4012
J 0
(3350 14900);
DISPLAY 0.510638 (3350 14900);
FORCEPROP 0 LAST $SEC 1
J 0
(3700 14975);
DISPLAY 0.680851 (3700 14975);
PAINT MONO (3700 14975);
DISPLAY INVISIBLE (3700 14975);
FORCEPROP 0 LAST CDS_SEC 1
J 0
(3700 14975);
DISPLAY 1.021277 (3700 14975);
DISPLAY INVISIBLE (3700 14975);
FORCEPROP 1 LASTPIN (3650 14900) $PN 1
J 0
(3662 14912);
DISPLAY 0.510638 (3662 14912);
PAINT MONO (3662 14912);
FORCEPROP 1 LASTPIN (3850 14900) $PN 2
J 0
(3812 14912);
DISPLAY 0.510638 (3812 14912);
PAINT MONO (3812 14912);
FORCEPROP 1 LAST PACK_TYPE 0402LF
J 0
(3875 14875);
DISPLAY 0.382979 (3875 14875);
FORCEPROP 1 LAST VALUE 0
J 2
(3900 14900);
DISPLAY 0.468085 (3900 14900);
FORCEPROP 1 LAST MATERIAL CHIP
J 0
(3525 14900);
DISPLAY 0.468085 (3525 14900);
FORCEPROP 1 LAST TOLERANCE 5%
J 0
(3925 14900);
DISPLAY 0.468085 (3925 14900);
FORCEPROP 0 LAST ROOM SCM_P12V_MAM_BOM1
J 0
(3625 14925);
DISPLAY 0.361702 (3625 14925);
PAINT RED (3625 14925);
FORCEPROP 1 LAST WATTAGE 1/16W
J 2
(3450 14875);
DISPLAY 0.468085 (3450 14875);
FORCEPROP 2 LAST CDS_LIB pure_quanta
J 0
(3750 14900);
DISPLAY INVISIBLE (3750 14900);
FORCEPROP 1 LAST PATH I73
J 0
(3700 15050);
DISPLAY 0.978723 (3700 15050);
PAINT WHITE (3700 15050);
DISPLAY INVISIBLE (3700 15050);
FORCEPROP 1 LAST PART_NUMBER CS00002JB13
J 0
(3500 14875);
DISPLAY 0.382979 (3500 14875);
DISPLAY INVISIBLE (3500 14875);
FORCEADD Q_RES..2
(3400 15250);
FORCEPROP 1 LAST LOCATION PR4526
J 0
(3450 15300);
DISPLAY 0.638298 (3450 15300);
FORCEPROP 0 LAST $SEC 1
J 0
(3450 15425);
DISPLAY 0.680851 (3450 15425);
PAINT MONO (3450 15425);
DISPLAY INVISIBLE (3450 15425);
FORCEPROP 0 LAST CDS_SEC 1
J 0
(3450 15425);
DISPLAY 1.021277 (3450 15425);
DISPLAY INVISIBLE (3450 15425);
FORCEPROP 1 LASTPIN (3400 15350) $PN 1
J 0
(3405 15312);
DISPLAY 0.787234 (3405 15312);
PAINT MONO (3405 15312);
FORCEPROP 1 LASTPIN (3400 15150) $PN 2
J 0
(3405 15160);
DISPLAY 0.787234 (3405 15160);
PAINT MONO (3405 15160);
FORCEPROP 1 LAST PACK_TYPE 0402LF
J 0
(3450 15150);
DISPLAY 0.510638 (3450 15150);
FORCEPROP 1 LAST MATERIAL CHIP
J 0
(3450 15200);
DISPLAY 0.510638 (3450 15200);
FORCEPROP 1 LAST WATTAGE 1/16W
J 0
(3450 15225);
DISPLAY 0.510638 (3450 15225);
FORCEPROP 0 LAST ROOM SCM_P12V_MAM_BOM1
J 0
(3450 15350);
DISPLAY 0.446809 (3450 15350);
PAINT RED (3450 15350);
FORCEPROP 1 LAST VALUE 10M
J 0
(3450 15275);
DISPLAY 0.510638 (3450 15275);
FORCEPROP 1 LAST TOLERANCE 1%
J 0
(3450 15250);
DISPLAY 0.510638 (3450 15250);
FORCEPROP 2 LAST CDS_LIB pure_quanta
J 0
(3400 15250);
DISPLAY INVISIBLE (3400 15250);
FORCEPROP 1 LAST PATH I74
J 0
(3450 15425);
DISPLAY 0.978723 (3450 15425);
PAINT WHITE (3450 15425);
DISPLAY INVISIBLE (3450 15425);
FORCEPROP 1 LAST PART_NUMBER CS61002FB02
J 0
(3450 15175);
DISPLAY 0.510638 (3450 15175);
DISPLAY INVISIBLE (3450 15175);
FORCEADD GND..1
(4050 14950);
FORCEPROP 3 LASTPIN (4050 15000) SIG_NAME GND\g
J 0
(4060 15010);
DISPLAY 0.659574 (4060 15010);
PAINT MONO (4060 15010);
DISPLAY INVISIBLE (4060 15010);
FORCEPROP 2 LAST CDS_LIB pure_quanta_power
J 0
(4050 14950);
DISPLAY INVISIBLE (4050 14950);
FORCEPROP 1 LAST SIZE 1B
J 0
(4125 14900);
DISPLAY 0.872340 (4125 14900);
PAINT GREEN (4125 14900);
DISPLAY INVISIBLE (4125 14900);
FORCEPROP 1 LAST HDL_POWER GND
J 0
(4050 15100);
DISPLAY 0.872340 (4050 15100);
PAINT GREEN (4050 15100);
DISPLAY INVISIBLE (4050 15100);
FORCEPROP 1 LAST PATH I75
J 0
(4125 14950);
DISPLAY 0.872340 (4125 14950);
PAINT AQUA (4125 14950);
DISPLAY INVISIBLE (4125 14950);
FORCEADD Q_RES..2
(4100 15150);
FORCEPROP 1 LAST LOCATION R4013
J 0
(4145 15275);
DISPLAY 0.638298 (4145 15275);
FORCEPROP 0 LAST $SEC 1
J 0
(4150 15325);
DISPLAY 0.680851 (4150 15325);
PAINT MONO (4150 15325);
DISPLAY INVISIBLE (4150 15325);
FORCEPROP 0 LAST CDS_SEC 1
J 0
(4150 15325);
DISPLAY 1.021277 (4150 15325);
DISPLAY INVISIBLE (4150 15325);
FORCEPROP 1 LASTPIN (4100 15250) $PN 1
J 0
(4105 15212);
DISPLAY 0.787234 (4105 15212);
PAINT MONO (4105 15212);
FORCEPROP 1 LASTPIN (4100 15050) $PN 2
J 0
(4105 15060);
DISPLAY 0.787234 (4105 15060);
PAINT MONO (4105 15060);
FORCEPROP 0 LAST ROOM SCM_P12V_MAM_BOM1
J 0
(4150 15325);
DISPLAY 0.446809 (4150 15325);
PAINT RED (4150 15325);
FORCEPROP 1 LAST VALUE 100K
J 0
(4145 15225);
DISPLAY 0.510638 (4145 15225);
FORCEPROP 1 LAST TOLERANCE 1%
J 0
(4145 15175);
DISPLAY 0.510638 (4145 15175);
FORCEPROP 1 LAST PACK_TYPE 0402LF
J 0
(4140 14975);
DISPLAY 0.510638 (4140 14975);
FORCEPROP 1 LAST MATERIAL CHIP
J 0
(4140 15075);
DISPLAY 0.510638 (4140 15075);
FORCEPROP 1 LAST WATTAGE 1/16W
J 0
(4140 15125);
DISPLAY 0.510638 (4140 15125);
FORCEPROP 2 LAST CDS_LIB pure_quanta
J 0
(4100 15150);
DISPLAY INVISIBLE (4100 15150);
FORCEPROP 1 LAST PATH I76
J 0
(4150 15325);
DISPLAY 0.978723 (4150 15325);
PAINT WHITE (4150 15325);
DISPLAY INVISIBLE (4150 15325);
FORCEPROP 1 LAST PART_NUMBER CS41002FB09
J 0
(4140 15025);
DISPLAY 0.510638 (4140 15025);
DISPLAY INVISIBLE (4140 15025);
FORCEADD VCCAUX15..1
(4300 15500);
FORCEPROP 3 LASTPIN (4300 15450) SIG_NAME P3V3_AUX\g
J 0
(4310 15460);
DISPLAY 0.659574 (4310 15460);
PAINT MONO (4310 15460);
DISPLAY INVISIBLE (4310 15460);
FORCEPROP 1 LAST HDL_POWER P3V3_AUX
J 1
(4300 15550);
DISPLAY 0.723404 (4300 15550);
PAINT GREEN (4300 15550);
FORCEPROP 2 LAST CDS_LIB pure_quanta_power
J 0
(4300 15500);
DISPLAY INVISIBLE (4300 15500);
FORCEPROP 1 LAST PATH I77
J 0
(4350 15525);
DISPLAY 0.872340 (4350 15525);
PAINT AQUA (4350 15525);
DISPLAY INVISIBLE (4350 15525);
FORCEADD Q_RES..2
(4525 15150);
FORCEPROP 1 LAST LOCATION R4015
J 0
(4570 15275);
DISPLAY 0.638298 (4570 15275);
FORCEPROP 0 LAST $SEC 1
J 0
(4575 15325);
DISPLAY 0.680851 (4575 15325);
PAINT MONO (4575 15325);
DISPLAY INVISIBLE (4575 15325);
FORCEPROP 0 LAST CDS_SEC 1
J 0
(4575 15325);
DISPLAY 1.021277 (4575 15325);
DISPLAY INVISIBLE (4575 15325);
FORCEPROP 1 LASTPIN (4525 15250) $PN 1
J 0
(4530 15212);
DISPLAY 0.787234 (4530 15212);
PAINT MONO (4530 15212);
FORCEPROP 1 LASTPIN (4525 15050) $PN 2
J 0
(4530 15060);
DISPLAY 0.787234 (4530 15060);
PAINT MONO (4530 15060);
FORCEPROP 1 LAST PACK_TYPE 0402LF
J 0
(4565 14975);
DISPLAY 0.510638 (4565 14975);
FORCEPROP 1 LAST WATTAGE 1/16W
J 0
(4565 15125);
DISPLAY 0.510638 (4565 15125);
FORCEPROP 1 LAST MATERIAL CHIP
J 0
(4565 15075);
DISPLAY 0.510638 (4565 15075);
FORCEPROP 1 LAST VALUE 100K
J 0
(4570 15225);
DISPLAY 0.510638 (4570 15225);
FORCEPROP 1 LAST TOLERANCE 1%
J 0
(4570 15175);
DISPLAY 0.510638 (4570 15175);
FORCEPROP 0 LAST ROOM SCM_P12V_MAM_BOM1
J 0
(4575 15325);
DISPLAY 0.446809 (4575 15325);
PAINT RED (4575 15325);
FORCEPROP 2 LAST CDS_LIB pure_quanta
J 0
(4525 15150);
DISPLAY INVISIBLE (4525 15150);
FORCEPROP 1 LAST PATH I78
J 0
(4575 15325);
DISPLAY 0.978723 (4575 15325);
PAINT WHITE (4575 15325);
DISPLAY INVISIBLE (4575 15325);
FORCEPROP 1 LAST PART_NUMBER CS41002FB09
J 0
(4565 15025);
DISPLAY 0.510638 (4565 15025);
DISPLAY INVISIBLE (4565 15025);
FORCEADD SCHOTTKY_AC..1
R 1
(3500 15850);
FORCEPROP 1 LAST LOCATION PD116
J 0
(3550 15875);
DISPLAY 0.723404 (3550 15875);
PAINT GREEN (3550 15875);
FORCEPROP 0 LAST $SEC 1
R 1
J 0
(3550 15925);
DISPLAY INVISIBLE (3550 15925);
FORCEPROP 0 LAST CDS_SEC 1
R 1
J 0
(3550 15925);
DISPLAY INVISIBLE (3550 15925);
FORCEPROP 0 LASTPIN (3500 15725) $PN A
R 1
J 2
(3490 15760);
DISPLAY 0.808511 (3490 15760);
FORCEPROP 0 LASTPIN (3500 15975) $PN C
R 1
J 0
(3490 15935);
DISPLAY 0.808511 (3490 15935);
FORCEPROP 1 LAST MATERIAL IC
J 0
(3550 15750);
DISPLAY 0.723404 (3550 15750);
PAINT GREEN (3550 15750);
FORCEPROP 2 LAST VALUE B340A-13-F
J 0
(3550 15825);
DISPLAY 0.638298 (3550 15825);
FORCEPROP 0 LAST PART_TYPE SMLF
J 0
(3550 16025);
DISPLAY 1.021277 (3550 16025);
DISPLAY INVISIBLE (3550 16025);
FORCEPROP 1 LAST NEEDS_NO_SIZE TRUE
R 1
J 0
(3550 15925);
DISPLAY 0.468085 (3550 15925);
PAINT GREEN (3550 15925);
DISPLAY INVISIBLE (3550 15925);
FORCEPROP 1 LAST CDS_LMAN_SYM_OUTLINE -75,50,75,-50
R 1
J 0
(3500 15850);
DISPLAY 0.468085 (3500 15850);
PAINT GREEN (3500 15850);
DISPLAY INVISIBLE (3500 15850);
FORCEPROP 2 LAST CDS_LIB pure_quanta
R 1
J 0
(3500 15850);
DISPLAY INVISIBLE (3500 15850);
FORCEPROP 1 LAST PATH I79
R 1
J 0
(3500 15850);
DISPLAY 0.723404 (3500 15850);
PAINT GREEN (3500 15850);
DISPLAY INVISIBLE (3500 15850);
FORCEPROP 1 LAST PART_NUMBER BC000340Z30
J 0
(3550 15775);
DISPLAY 0.595745 (3550 15775);
PAINT GREEN (3550 15775);
DISPLAY INVISIBLE (3550 15775);
FORCEADD Q_CAP..1
(-525 11650);
FORCEPROP 1 LAST LOCATION PC2229
J 0
(-475 11700);
DISPLAY 0.638298 (-475 11700);
FORCEPROP 0 LAST $SEC 1
J 0
(-475 11800);
DISPLAY INVISIBLE (-475 11800);
FORCEPROP 0 LAST CDS_SEC 1
J 0
(-475 11800);
DISPLAY INVISIBLE (-475 11800);
FORCEPROP 1 LASTPIN (-525 11750) $PN 1
J 0
(-515 11730);
DISPLAY 0.787234 (-515 11730);
PAINT MONO (-515 11730);
DISPLAY INVISIBLE (-515 11730);
FORCEPROP 1 LASTPIN (-525 11550) $PN 2
J 0
(-515 11530);
DISPLAY 0.787234 (-515 11530);
PAINT MONO (-515 11530);
DISPLAY INVISIBLE (-515 11530);
FORCEPROP 1 LAST PACK_TYPE 0402
J 0
(-475 11575);
DISPLAY 0.510638 (-475 11575);
FORCEPROP 1 LAST VOLTAGE 16V
J 0
(-475 11650);
DISPLAY 0.510638 (-475 11650);
FORCEPROP 1 LAST MATERIAL X7R
J 0
(-475 11625);
DISPLAY 0.510638 (-475 11625);
PAINT RED (-475 11625);
FORCEPROP 0 LAST ROOM SCM_P12V_MPS_BOM2
J 0
(-475 11750);
DISPLAY 0.446809 (-475 11750);
PAINT RED (-475 11750);
FORCEPROP 1 LAST VALUE 0.22UF
J 0
(-475 11675);
DISPLAY 0.510638 (-475 11675);
FORCEPROP 2 LAST CDS_LIB pure_quanta
J 0
(-525 11650);
DISPLAY INVISIBLE (-525 11650);
FORCEPROP 1 LAST TOLERANCE 10%
J 0
(-475 11600);
DISPLAY 0.638298 (-475 11600);
DISPLAY INVISIBLE (-475 11600);
FORCEPROP 1 LAST PATH I8
J 0
(-475 11800);
DISPLAY 0.978723 (-475 11800);
PAINT WHITE (-475 11800);
DISPLAY INVISIBLE (-475 11800);
FORCEPROP 1 LAST PART_NUMBER CH4223K1B00
J 0
(-475 11600);
DISPLAY 0.510638 (-475 11600);
DISPLAY INVISIBLE (-475 11600);
FORCEADD Q_CAP..1
(3975 15825);
FORCEPROP 1 LAST LOCATION PC2238
J 0
(4025 15925);
DISPLAY 0.638298 (4025 15925);
FORCEPROP 0 LAST $SEC 1
J 0
(4025 15975);
DISPLAY 0.680851 (4025 15975);
PAINT MONO (4025 15975);
DISPLAY INVISIBLE (4025 15975);
FORCEPROP 0 LAST CDS_SEC 1
J 0
(4025 15975);
DISPLAY 1.021277 (4025 15975);
DISPLAY INVISIBLE (4025 15975);
FORCEPROP 1 LASTPIN (3975 15925) $PN 1
J 0
(3985 15905);
DISPLAY 0.787234 (3985 15905);
PAINT MONO (3985 15905);
FORCEPROP 1 LASTPIN (3975 15725) $PN 2
J 0
(3985 15705);
DISPLAY 0.787234 (3985 15705);
PAINT MONO (3985 15705);
FORCEPROP 1 LAST VOLTAGE 25V
J 0
(4025 15825);
DISPLAY 0.638298 (4025 15825);
FORCEPROP 1 LAST VALUE 0.1UF
J 0
(4025 15875);
DISPLAY 0.638298 (4025 15875);
FORCEPROP 1 LAST PACK_TYPE 0402
J 0
(4025 15675);
DISPLAY 0.638298 (4025 15675);
FORCEPROP 1 LAST MATERIAL X7R
J 0
(4025 15775);
DISPLAY 0.638298 (4025 15775);
FORCEPROP 1 LAST TOLERANCE 10%
J 0
(4025 15775);
DISPLAY 0.978723 (4025 15775);
DISPLAY INVISIBLE (4025 15775);
FORCEPROP 2 LAST CDS_LIB pure_quanta
J 0
(3975 15825);
DISPLAY INVISIBLE (3975 15825);
FORCEPROP 1 LAST PATH I80
J 0
(4025 15975);
DISPLAY 0.978723 (4025 15975);
PAINT WHITE (4025 15975);
DISPLAY INVISIBLE (4025 15975);
FORCEPROP 1 LAST PART_NUMBER CH4104K1B00
J 0
(4025 15725);
DISPLAY 0.638298 (4025 15725);
DISPLAY INVISIBLE (4025 15725);
FORCEADD Q_CAP..1
(4400 15825);
FORCEPROP 1 LAST LOCATION PC2240
J 0
(4450 15925);
DISPLAY 0.638298 (4450 15925);
FORCEPROP 0 LAST $SEC 1
J 0
(4450 15975);
DISPLAY INVISIBLE (4450 15975);
FORCEPROP 0 LAST CDS_SEC 1
J 0
(4450 15975);
DISPLAY INVISIBLE (4450 15975);
FORCEPROP 1 LASTPIN (4400 15925) $PN 1
J 0
(4410 15905);
DISPLAY 0.787234 (4410 15905);
PAINT MONO (4410 15905);
DISPLAY INVISIBLE (4410 15905);
FORCEPROP 1 LASTPIN (4400 15725) $PN 2
J 0
(4410 15705);
DISPLAY 0.787234 (4410 15705);
PAINT MONO (4410 15705);
DISPLAY INVISIBLE (4410 15705);
FORCEPROP 1 LAST MATERIAL X6S
J 0
(4450 15775);
DISPLAY 0.638298 (4450 15775);
FORCEPROP 1 LAST VOLTAGE 16V
J 0
(4450 15825);
DISPLAY 0.638298 (4450 15825);
FORCEPROP 1 LAST PACK_TYPE C0805
J 0
(4450 15675);
DISPLAY 0.638298 (4450 15675);
FORCEPROP 1 LAST VALUE 10UF
J 0
(4450 15875);
DISPLAY 0.638298 (4450 15875);
FORCEPROP 1 LAST TOLERANCE 10%
J 0
(4450 15775);
DISPLAY 0.978723 (4450 15775);
DISPLAY INVISIBLE (4450 15775);
FORCEPROP 2 LAST CDS_LIB pure_quanta
J 0
(4400 15825);
DISPLAY INVISIBLE (4400 15825);
FORCEPROP 1 LAST PATH I81
J 0
(4450 15975);
DISPLAY 0.978723 (4450 15975);
PAINT WHITE (4450 15975);
DISPLAY INVISIBLE (4450 15975);
FORCEPROP 1 LAST PART_NUMBER CH6103KEA01
J 0
(4450 15725);
DISPLAY 0.638298 (4450 15725);
DISPLAY INVISIBLE (4450 15725);
FORCEADD OFFPAGE..2
(5000 14900);
FORCEPROP 2 LAST $XR1 81 
J 0
(5189 14900);
DISPLAY 0.638298 (5189 14900);
PAINT MONO (5189 14900);
FORCEPROP 2 LAST $XR0 152 
J 0
(5189 14900);
DISPLAY 0.638298 (5189 14900);
PAINT MONO (5189 14900);
FORCEPROP 2 LAST CDS_LIB standard
J 0
(5000 14900);
DISPLAY INVISIBLE (5000 14900);
FORCEPROP 1 LAST OFFPAGE TRUE
J 0
(5325 14775);
DISPLAY 0.872340 (5325 14775);
DISPLAY INVISIBLE (5325 14775);
FORCEPROP 1 LAST COMMENT_BODY TRUE
J 0
(4955 14805);
DISPLAY 0.872340 (4955 14805);
PAINT GREEN (4955 14805);
DISPLAY INVISIBLE (4955 14805);
FORCEPROP 2 LAST PATH I82
J 0
(5175 14975);
DISPLAY 0.680851 (5175 14975);
DISPLAY INVISIBLE (5175 14975);
FORCEADD GND..1
(4800 15525);
FORCEPROP 3 LASTPIN (4800 15575) SIG_NAME GND\g
J 0
(4810 15585);
DISPLAY 0.659574 (4810 15585);
PAINT MONO (4810 15585);
DISPLAY INVISIBLE (4810 15585);
FORCEPROP 2 LAST CDS_LIB pure_quanta_power
J 0
(4800 15525);
DISPLAY INVISIBLE (4800 15525);
FORCEPROP 1 LAST SIZE 1B
J 0
(4875 15475);
DISPLAY 0.872340 (4875 15475);
PAINT GREEN (4875 15475);
DISPLAY INVISIBLE (4875 15475);
FORCEPROP 1 LAST HDL_POWER GND
J 0
(4800 15675);
DISPLAY 0.872340 (4800 15675);
PAINT GREEN (4800 15675);
DISPLAY INVISIBLE (4800 15675);
FORCEPROP 1 LAST PATH I83
J 0
(4875 15525);
DISPLAY 0.872340 (4875 15525);
PAINT AQUA (4875 15525);
DISPLAY INVISIBLE (4875 15525);
FORCEADD Q_CAP..1
(4800 15825);
FORCEPROP 1 LAST LOCATION PC2242
J 0
(4850 15925);
DISPLAY 0.680851 (4850 15925);
FORCEPROP 0 LAST $SEC 1
J 0
(4850 15975);
DISPLAY INVISIBLE (4850 15975);
FORCEPROP 0 LAST CDS_SEC 1
J 0
(4850 15975);
DISPLAY INVISIBLE (4850 15975);
FORCEPROP 1 LASTPIN (4800 15925) $PN 1
J 0
(4810 15905);
DISPLAY 0.787234 (4810 15905);
PAINT MONO (4810 15905);
DISPLAY INVISIBLE (4810 15905);
FORCEPROP 1 LASTPIN (4800 15725) $PN 2
J 0
(4810 15705);
DISPLAY 0.787234 (4810 15705);
PAINT MONO (4810 15705);
DISPLAY INVISIBLE (4810 15705);
FORCEPROP 1 LAST VOLTAGE 16V
J 0
(4850 15825);
DISPLAY 0.638298 (4850 15825);
FORCEPROP 1 LAST VALUE 22UF
J 0
(4850 15875);
DISPLAY 0.638298 (4850 15875);
FORCEPROP 1 LAST MATERIAL X6S
J 0
(4850 15775);
DISPLAY 0.638298 (4850 15775);
FORCEPROP 1 LAST PACK_TYPE C0805
J 0
(4850 15675);
DISPLAY 0.638298 (4850 15675);
FORCEPROP 2 LAST CDS_LIB pure_quanta
J 0
(4800 15825);
DISPLAY INVISIBLE (4800 15825);
FORCEPROP 1 LAST TOLERANCE 20%
J 0
(4589 15785);
DISPLAY 0.787234 (4589 15785);
PAINT GREEN (4589 15785);
DISPLAY INVISIBLE (4589 15785);
FORCEPROP 1 LAST PATH I84
J 0
(4850 15975);
DISPLAY 0.978723 (4850 15975);
PAINT WHITE (4850 15975);
DISPLAY INVISIBLE (4850 15975);
FORCEPROP 1 LAST PART_NUMBER CH6223MEA01
J 0
(4850 15725);
DISPLAY 0.638298 (4850 15725);
DISPLAY INVISIBLE (4850 15725);
FORCEADD UNIVERSAL_POWER..1
R 2
(4800 16125);
FORCEPROP 3 LASTPIN (4800 16075) SIG_NAME P12V_SCM_R\g
J 0
(4810 16085);
DISPLAY 0.659574 (4810 16085);
PAINT MONO (4810 16085);
DISPLAY INVISIBLE (4810 16085);
FORCEPROP 1 LAST HDL_POWER P12V_SCM_R
J 1
(4825 16175);
DISPLAY 0.723404 (4825 16175);
PAINT GREEN (4825 16175);
FORCEPROP 2 LAST CDS_LIB pure_quanta_power
J 0
(4800 16125);
DISPLAY INVISIBLE (4800 16125);
FORCEPROP 1 LAST PATH I85
J 2
(4750 16150);
DISPLAY 0.872340 (4750 16150);
PAINT AQUA (4750 16150);
DISPLAY INVISIBLE (4750 16150);
FORCEADD MAX15090BEWIT..1
(2275 14900);
FORCEPROP 1 LAST LOCATION PU300
J 0
(2022 15628);
DISPLAY 0.723404 (2022 15628);
PAINT GREEN (2022 15628);
FORCEPROP 0 LAST $SEC 1
J 0
(2025 15775);
DISPLAY 0.680851 (2025 15775);
PAINT MONO (2025 15775);
DISPLAY INVISIBLE (2025 15775);
FORCEPROP 0 LAST CDS_SEC 1
J 0
(2025 15775);
DISPLAY 1.021277 (2025 15775);
DISPLAY INVISIBLE (2025 15775);
FORCEPROP 0 LASTPIN (1875 14600) $PN B1
J 2
(1865 14610);
DISPLAY 0.680851 (1865 14610);
PAINT MONO (1865 14610);
FORCEPROP 0 LASTPIN (2675 14600) $PN A7
J 0
(2685 14610);
DISPLAY 0.680851 (2685 14610);
PAINT MONO (2685 14610);
FORCEPROP 0 LASTPIN (1875 14500) $PN B7
J 2
(1865 14510);
DISPLAY 0.680851 (1865 14510);
PAINT MONO (1865 14510);
FORCEPROP 0 LASTPIN (2675 14800) $PN C7
J 0
(2685 14810);
DISPLAY 0.680851 (2685 14810);
PAINT MONO (2685 14810);
FORCEPROP 0 LASTPIN (2675 15000) $PN A6
J 0
(2685 15010);
DISPLAY 0.680851 (2685 15010);
PAINT MONO (2685 15010);
FORCEPROP 0 LASTPIN (2675 14500) $PN B2
J 0
(2685 14510);
DISPLAY 0.680851 (2685 14510);
PAINT MONO (2685 14510);
FORCEPROP 0 LASTPIN (2675 14450) $PN C1
J 0
(2685 14460);
DISPLAY 0.680851 (2685 14460);
PAINT MONO (2685 14460);
FORCEPROP 0 LASTPIN (2675 14400) $PN C2
J 0
(2685 14410);
DISPLAY 0.680851 (2685 14410);
PAINT MONO (2685 14410);
FORCEPROP 0 LASTPIN (1875 15400) $PN A3
J 2
(1865 15410);
DISPLAY 0.680851 (1865 15410);
PAINT MONO (1865 15410);
FORCEPROP 0 LASTPIN (1875 15350) $PN A5
J 2
(1865 15360);
DISPLAY 0.680851 (1865 15360);
PAINT MONO (1865 15360);
FORCEPROP 0 LASTPIN (1875 15300) $PN B3
J 2
(1865 15310);
DISPLAY 0.680851 (1865 15310);
PAINT MONO (1865 15310);
FORCEPROP 0 LASTPIN (1875 15250) $PN B5
J 2
(1865 15260);
DISPLAY 0.680851 (1865 15260);
PAINT MONO (1865 15260);
FORCEPROP 0 LASTPIN (1875 15200) $PN C3
J 2
(1865 15210);
DISPLAY 0.680851 (1865 15210);
PAINT MONO (1865 15210);
FORCEPROP 0 LASTPIN (1875 15150) $PN C5
J 2
(1865 15160);
DISPLAY 0.680851 (1865 15160);
PAINT MONO (1865 15160);
FORCEPROP 0 LASTPIN (1875 15100) $PN D5
J 2
(1865 15110);
DISPLAY 0.680851 (1865 15110);
PAINT MONO (1865 15110);
FORCEPROP 0 LASTPIN (2675 14700) $PN A1
J 0
(2685 14710);
DISPLAY 0.680851 (2685 14710);
PAINT MONO (2685 14710);
FORCEPROP 0 LASTPIN (2675 15400) $PN A4
J 0
(2685 15410);
DISPLAY 0.680851 (2685 15410);
PAINT MONO (2685 15410);
FORCEPROP 0 LASTPIN (2675 15350) $PN B4
J 0
(2685 15360);
DISPLAY 0.680851 (2685 15360);
PAINT MONO (2685 15360);
FORCEPROP 0 LASTPIN (2675 15300) $PN B6
J 0
(2685 15310);
DISPLAY 0.680851 (2685 15310);
PAINT MONO (2685 15310);
FORCEPROP 0 LASTPIN (2675 15250) $PN C4
J 0
(2685 15260);
DISPLAY 0.680851 (2685 15260);
PAINT MONO (2685 15260);
FORCEPROP 0 LASTPIN (2675 15200) $PN C6
J 0
(2685 15210);
DISPLAY 0.680851 (2685 15210);
PAINT MONO (2685 15210);
FORCEPROP 0 LASTPIN (2675 15150) $PN D4
J 0
(2685 15160);
DISPLAY 0.680851 (2685 15160);
PAINT MONO (2685 15160);
FORCEPROP 0 LASTPIN (2675 15100) $PN D6
J 0
(2685 15110);
DISPLAY 0.680851 (2685 15110);
PAINT MONO (2685 15110);
FORCEPROP 0 LASTPIN (1875 14700) $PN D3
J 2
(1865 14710);
DISPLAY 0.680851 (1865 14710);
PAINT MONO (1865 14710);
FORCEPROP 0 LASTPIN (2675 14900) $PN D7
J 0
(2685 14910);
DISPLAY 0.680851 (2685 14910);
PAINT MONO (2685 14910);
FORCEPROP 0 LASTPIN (1875 14900) $PN D1
J 2
(1865 14910);
DISPLAY 0.680851 (1865 14910);
PAINT MONO (1865 14910);
FORCEPROP 0 LASTPIN (1875 14800) $PN D2
J 2
(1865 14810);
DISPLAY 0.680851 (1865 14810);
PAINT MONO (1865 14810);
FORCEPROP 0 LASTPIN (1875 15000) $PN A2
J 2
(1865 15010);
DISPLAY 0.680851 (1865 15010);
PAINT MONO (1865 15010);
FORCEPROP 0 LAST ROOM SCM_P12V_MAM_BOM1
J 0
(2025 15825);
DISPLAY 0.680851 (2025 15825);
PAINT RED (2025 15825);
FORCEPROP 2 LAST PART_TYPE SMLF
J 0
(2025 15725);
DISPLAY 1.021277 (2025 15725);
FORCEPROP 2 LAST VALUE MAX15090BEWI+T
J 0
(2025 15675);
DISPLAY 1.021277 (2025 15675);
FORCEPROP 1 LAST MATERIAL IC
J 0
(2022 15455);
DISPLAY 0.723404 (2022 15455);
PAINT GREEN (2022 15455);
FORCEPROP 1 LAST CDS_LMAN_SYM_OUTLINE -250,550,250,-550
J 0
(2275 14900);
DISPLAY 0.468085 (2275 14900);
PAINT GREEN (2275 14900);
DISPLAY INVISIBLE (2275 14900);
FORCEPROP 2 LAST CDS_LIB pure_quanta
J 0
(2275 14900);
DISPLAY INVISIBLE (2275 14900);
FORCEPROP 1 LAST PIN_NAMES_ROTATE TRUE
J 0
(2275 14900);
DISPLAY 0.489362 (2275 14900);
PAINT GREEN (2275 14900);
DISPLAY INVISIBLE (2275 14900);
FORCEPROP 1 LAST PATH I86
J 0
(2525 14350);
DISPLAY 0.723404 (2525 14350);
PAINT GREEN (2525 14350);
DISPLAY INVISIBLE (2525 14350);
FORCEPROP 1 LAST PART_NUMBER AL015080B00
J 0
(2022 15544);
DISPLAY 0.723404 (2022 15544);
PAINT GREEN (2022 15544);
DISPLAY INVISIBLE (2022 15544);
FORCEADD Q_RES..1
(3175 12500);
FORCEPROP 1 LAST LOCATION R8012
J 0
(2925 12500);
DISPLAY 0.638298 (2925 12500);
FORCEPROP 2 LAST SEC 1
J 0
(3125 12700);
DISPLAY 0.680851 (3125 12700);
PAINT MONO (3125 12700);
DISPLAY INVISIBLE (3125 12700);
FORCEPROP 1 LASTPIN (3075 12500) $PN 1
J 0
(3087 12512);
DISPLAY 0.787234 (3087 12512);
PAINT MONO (3087 12512);
FORCEPROP 1 LASTPIN (3275 12500) $PN 2
J 0
(3237 12512);
DISPLAY 0.787234 (3237 12512);
PAINT MONO (3237 12512);
FORCEPROP 1 LAST PACK_TYPE 0402LF
J 0
(3225 12450);
DISPLAY 0.595745 (3225 12450);
FORCEPROP 1 LAST MATERIAL CHIP
J 0
(3000 12450);
DISPLAY 0.595745 (3000 12450);
FORCEPROP 1 LAST VALUE 0
J 2
(3325 12500);
DISPLAY 0.595745 (3325 12500);
FORCEPROP 1 LAST TOLERANCE 5%
J 0
(3350 12500);
DISPLAY 0.595745 (3350 12500);
FORCEPROP 0 LAST ROOM SCM_P12V_MPS_BOM2
J 0
(2975 12575);
DISPLAY 0.553191 (2975 12575);
PAINT RED (2975 12575);
FORCEPROP 1 LAST WATTAGE 1/16W
J 2
(3075 12450);
DISPLAY 0.595745 (3075 12450);
DISPLAY INVISIBLE (3075 12450);
FORCEPROP 2 LAST SEC_TYPE 0402LF
J 0
(3125 12700);
DISPLAY 0.680851 (3125 12700);
DISPLAY INVISIBLE (3125 12700);
FORCEPROP 2 LAST CDS_LIB pure_quanta
J 0
(3175 12500);
DISPLAY INVISIBLE (3175 12500);
FORCEPROP 1 LAST PATH I89
J 0
(3125 12650);
DISPLAY 0.978723 (3125 12650);
PAINT WHITE (3125 12650);
DISPLAY INVISIBLE (3125 12650);
FORCEPROP 1 LAST PART_NUMBER CS00002JB13
J 0
(3000 12450);
DISPLAY 0.595745 (3000 12450);
DISPLAY INVISIBLE (3000 12450);
FORCEADD MOSFET_NCH_GDS_ESD_PROTECTED..1
(-775 13175);
FORCEPROP 1 LAST LOCATION Q39
J 0
(-633 13139);
DISPLAY 0.723404 (-633 13139);
PAINT GREEN (-633 13139);
FORCEPROP 0 LAST $SEC 1
J 0
(-625 13325);
DISPLAY 0.680851 (-625 13325);
PAINT MONO (-625 13325);
DISPLAY INVISIBLE (-625 13325);
FORCEPROP 0 LAST CDS_SEC 1
J 0
(-600 13300);
DISPLAY 1.021277 (-600 13300);
DISPLAY INVISIBLE (-600 13300);
FORCEPROP 0 LASTPIN (-750 13375) $PN D
R 1
J 0
(-760 13385);
DISPLAY 0.680851 (-760 13385);
PAINT MONO (-760 13385);
FORCEPROP 0 LASTPIN (-950 13175) $PN G
J 2
(-960 13185);
DISPLAY 0.680851 (-960 13185);
PAINT MONO (-960 13185);
FORCEPROP 0 LASTPIN (-750 12975) $PN S
R 1
J 2
(-760 12965);
DISPLAY 0.680851 (-760 12965);
PAINT MONO (-760 12965);
FORCEPROP 1 LAST MATERIAL IC
J 0
(-633 13030);
DISPLAY 0.723404 (-633 13030);
PAINT GREEN (-633 13030);
FORCEPROP 2 LAST VALUE 2N7002K
J 0
(-625 13225);
DISPLAY 0.680851 (-625 13225);
FORCEPROP 2 LAST PART_TYPE SMLF
J 0
(-625 13275);
DISPLAY 0.680851 (-625 13275);
FORCEPROP 1 LAST NEEDS_NO_SIZE TRUE
J 0
(-650 13065);
DISPLAY 0.723404 (-650 13065);
PAINT GREEN (-650 13065);
DISPLAY INVISIBLE (-650 13065);
FORCEPROP 2 LAST CDS_LIB pure_quanta
J 0
(-775 13175);
DISPLAY INVISIBLE (-775 13175);
FORCEPROP 1 LAST CDS_LMAN_SYM_OUTLINE -125,150,125,-150
J 0
(-775 13175);
DISPLAY 0.468085 (-775 13175);
PAINT GREEN (-775 13175);
DISPLAY INVISIBLE (-775 13175);
FORCEPROP 1 LAST PATH I9
J 0
(-650 13025);
DISPLAY 0.723404 (-650 13025);
PAINT GREEN (-650 13025);
DISPLAY INVISIBLE (-650 13025);
FORCEPROP 1 LAST PART_NUMBER BAM70020002
J 0
(-633 13087);
DISPLAY 0.723404 (-633 13087);
PAINT GREEN (-633 13087);
DISPLAY INVISIBLE (-633 13087);
FORCEADD OFFPAGE..2
(4150 12900);
FORCEPROP 2 LAST $XR1 81 
J 0
(4459 12900);
DISPLAY 0.638298 (4459 12900);
PAINT MONO (4459 12900);
FORCEPROP 2 LAST $XR0 152 
J 0
(4339 12900);
DISPLAY 0.638298 (4339 12900);
PAINT MONO (4339 12900);
FORCEPROP 2 LAST CDS_LIB standard
J 0
(4150 12900);
DISPLAY INVISIBLE (4150 12900);
FORCEPROP 1 LAST OFFPAGE TRUE
J 0
(4475 12775);
DISPLAY 0.872340 (4475 12775);
DISPLAY INVISIBLE (4475 12775);
FORCEPROP 1 LAST COMMENT_BODY TRUE
J 0
(4105 12805);
DISPLAY 0.872340 (4105 12805);
PAINT GREEN (4105 12805);
DISPLAY INVISIBLE (4105 12805);
FORCEPROP 2 LAST PATH I90
J 0
(4325 12975);
DISPLAY 0.680851 (4325 12975);
DISPLAY INVISIBLE (4325 12975);
FORCEADD Q_RES..1
(3750 14800);
FORCEPROP 1 LAST LOCATION R8030
J 0
(3350 14800);
DISPLAY 0.638298 (3350 14800);
FORCEPROP 0 LAST $SEC 1
J 0
(3925 14850);
DISPLAY 0.680851 (3925 14850);
PAINT MONO (3925 14850);
DISPLAY INVISIBLE (3925 14850);
FORCEPROP 0 LAST CDS_SEC 1
J 0
(3925 14850);
DISPLAY 0.680851 (3925 14850);
DISPLAY INVISIBLE (3925 14850);
FORCEPROP 1 LASTPIN (3650 14800) $PN 1
J 0
(3662 14812);
DISPLAY 0.787234 (3662 14812);
PAINT MONO (3662 14812);
FORCEPROP 1 LASTPIN (3850 14800) $PN 2
J 0
(3812 14812);
DISPLAY 0.787234 (3812 14812);
PAINT MONO (3812 14812);
FORCEPROP 0 LAST ROOM SCM_P12V_MAM_BOM1
J 0
(3550 14725);
DISPLAY 0.553191 (3550 14725);
PAINT RED (3550 14725);
FORCEPROP 1 LAST PACK_TYPE 0402LF
J 0
(3900 14750);
DISPLAY 0.595745 (3900 14750);
FORCEPROP 1 LAST TOLERANCE 5%
J 0
(3925 14800);
DISPLAY 0.595745 (3925 14800);
FORCEPROP 1 LAST VALUE 0
J 2
(3900 14800);
DISPLAY 0.595745 (3900 14800);
FORCEPROP 1 LAST MATERIAL CHIP
J 0
(3525 14800);
DISPLAY 0.595745 (3525 14800);
FORCEPROP 1 LAST WATTAGE 1/16W
J 2
(3550 14750);
DISPLAY 0.595745 (3550 14750);
FORCEPROP 2 LAST CDS_LIB pure_quanta
J 0
(3750 14800);
DISPLAY INVISIBLE (3750 14800);
FORCEPROP 1 LAST PATH I91
J 0
(3700 14950);
DISPLAY 0.978723 (3700 14950);
PAINT WHITE (3700 14950);
DISPLAY INVISIBLE (3700 14950);
FORCEPROP 1 LAST PART_NUMBER CS00002JB13
J 0
(3575 14750);
DISPLAY 0.595745 (3575 14750);
DISPLAY INVISIBLE (3575 14750);
FORCEADD OFFPAGE..2
(5000 14800);
FORCEPROP 2 LAST $XR1 257 
J 0
(5189 14800);
DISPLAY 0.638298 (5189 14800);
PAINT MONO (5189 14800);
FORCEPROP 2 LAST $XR0 152 
J 0
(5189 14800);
DISPLAY 0.638298 (5189 14800);
PAINT MONO (5189 14800);
FORCEPROP 2 LAST CDS_LIB standard
J 0
(5000 14800);
DISPLAY INVISIBLE (5000 14800);
FORCEPROP 1 LAST OFFPAGE TRUE
J 0
(5325 14675);
DISPLAY 0.872340 (5325 14675);
DISPLAY INVISIBLE (5325 14675);
FORCEPROP 1 LAST COMMENT_BODY TRUE
J 0
(4955 14705);
DISPLAY 0.872340 (4955 14705);
PAINT GREEN (4955 14705);
DISPLAY INVISIBLE (4955 14705);
FORCEPROP 2 LAST PATH I92
J 0
(5175 14875);
DISPLAY 0.680851 (5175 14875);
DISPLAY INVISIBLE (5175 14875);
FORCEADD Q_RES..1
(3450 11100);
FORCEPROP 1 LAST LOCATION R8031
J 0
(3100 11100);
DISPLAY 0.638298 (3100 11100);
FORCEPROP 0 LAST $SEC 1
J 0
(3625 11150);
DISPLAY 0.680851 (3625 11150);
PAINT MONO (3625 11150);
DISPLAY INVISIBLE (3625 11150);
FORCEPROP 0 LAST CDS_SEC 1
J 0
(3625 11150);
DISPLAY 0.680851 (3625 11150);
DISPLAY INVISIBLE (3625 11150);
FORCEPROP 1 LASTPIN (3350 11100) $PN 1
J 0
(3362 11112);
DISPLAY 0.787234 (3362 11112);
PAINT MONO (3362 11112);
FORCEPROP 1 LASTPIN (3550 11100) $PN 2
J 0
(3512 11112);
DISPLAY 0.787234 (3512 11112);
PAINT MONO (3512 11112);
FORCEPROP 1 LAST WATTAGE 1/16W
J 2
(3250 11050);
DISPLAY 0.595745 (3250 11050);
FORCEPROP 1 LAST PACK_TYPE 0402LF
J 0
(3600 11050);
DISPLAY 0.595745 (3600 11050);
FORCEPROP 1 LAST TOLERANCE 5%
J 0
(3625 11100);
DISPLAY 0.595745 (3625 11100);
FORCEPROP 1 LAST MATERIAL CHIP
J 0
(3225 11100);
DISPLAY 0.595745 (3225 11100);
FORCEPROP 1 LAST VALUE 0
J 2
(3600 11100);
DISPLAY 0.595745 (3600 11100);
FORCEPROP 0 LAST ROOM SCM_P12V_MPS_BOM2
J 0
(3175 11000);
DISPLAY 0.553191 (3175 11000);
PAINT RED (3175 11000);
FORCEPROP 2 LAST CDS_LIB pure_quanta
J 0
(3450 11100);
DISPLAY INVISIBLE (3450 11100);
FORCEPROP 1 LAST PATH I93
J 0
(3400 11250);
DISPLAY 0.978723 (3400 11250);
PAINT WHITE (3400 11250);
DISPLAY INVISIBLE (3400 11250);
FORCEPROP 1 LAST PART_NUMBER CS00002JB13
J 0
(3275 11050);
DISPLAY 0.595745 (3275 11050);
DISPLAY INVISIBLE (3275 11050);
FORCEADD OFFPAGE..2
(4525 11100);
FORCEPROP 2 LAST $XR1 257 
J 0
(4834 11100);
DISPLAY 0.638298 (4834 11100);
PAINT MONO (4834 11100);
FORCEPROP 2 LAST $XR0 152 
J 0
(4714 11100);
DISPLAY 0.638298 (4714 11100);
PAINT MONO (4714 11100);
FORCEPROP 2 LAST CDS_LIB standard
J 0
(4525 11100);
DISPLAY INVISIBLE (4525 11100);
FORCEPROP 1 LAST OFFPAGE TRUE
J 0
(4850 10975);
DISPLAY 0.872340 (4850 10975);
DISPLAY INVISIBLE (4850 10975);
FORCEPROP 1 LAST COMMENT_BODY TRUE
J 0
(4480 11005);
DISPLAY 0.872340 (4480 11005);
PAINT GREEN (4480 11005);
DISPLAY INVISIBLE (4480 11005);
FORCEPROP 2 LAST PATH I94
J 0
(4700 11175);
DISPLAY 0.680851 (4700 11175);
DISPLAY INVISIBLE (4700 11175);
FORCEADD RS31312R..1
(1625 12025);
FORCEPROP 1 LAST LOCATION PU299
J 0
(1375 12650);
DISPLAY 0.723404 (1375 12650);
PAINT GREEN (1375 12650);
FORCEPROP 2 LAST SEC 1
J 0
(1400 12975);
DISPLAY 0.680851 (1400 12975);
PAINT MONO (1400 12975);
DISPLAY INVISIBLE (1400 12975);
FORCEPROP 2 LASTPIN (2025 11900) $PN 12
J 0
(2035 11910);
DISPLAY 0.680851 (2035 11910);
PAINT MONO (2035 11910);
FORCEPROP 2 LASTPIN (1225 12150) $PN 1
J 2
(1215 12160);
DISPLAY 0.680851 (1215 12160);
PAINT MONO (1215 12160);
FORCEPROP 2 LASTPIN (1225 11950) $PN 3
J 2
(1215 11960);
DISPLAY 0.680851 (1215 11960);
PAINT MONO (1215 11960);
FORCEPROP 2 LASTPIN (2025 11650) $PN 9
J 0
(2035 11660);
DISPLAY 0.680851 (2035 11660);
PAINT MONO (2035 11660);
FORCEPROP 2 LASTPIN (1225 11550) $PN 7
J 2
(1215 11560);
DISPLAY 0.680851 (1215 11560);
PAINT MONO (1215 11560);
FORCEPROP 2 LASTPIN (2025 11550) $PN 8
J 0
(2035 11560);
DISPLAY 0.680851 (2035 11560);
PAINT MONO (2035 11560);
FORCEPROP 2 LASTPIN (1225 11750) $PN 5
J 2
(1215 11760);
DISPLAY 0.680851 (1215 11760);
PAINT MONO (1215 11760);
FORCEPROP 2 LASTPIN (1225 12050) $PN 2
J 2
(1215 12060);
DISPLAY 0.680851 (1215 12060);
PAINT MONO (1215 12060);
FORCEPROP 2 LASTPIN (2025 11800) $PN 11
J 0
(2035 11810);
DISPLAY 0.680851 (2035 11810);
PAINT MONO (2035 11810);
FORCEPROP 2 LASTPIN (2025 12500) $PN 10
J 0
(2035 12510);
DISPLAY 0.680851 (2035 12510);
PAINT MONO (2035 12510);
FORCEPROP 2 LASTPIN (1225 11650) $PN 6
J 2
(1215 11660);
DISPLAY 0.680851 (1215 11660);
PAINT MONO (1215 11660);
FORCEPROP 2 LASTPIN (1225 11850) $PN 4
J 2
(1215 11860);
DISPLAY 0.680851 (1215 11860);
PAINT MONO (1215 11860);
FORCEPROP 2 LASTPIN (1225 12500) $PN 21_22
J 2
(1215 12510);
DISPLAY 0.680851 (1215 12510);
PAINT MONO (1215 12510);
FORCEPROP 2 LASTPIN (1225 12450) $PN 23
J 2
(1215 12460);
DISPLAY 0.680851 (1215 12460);
PAINT MONO (1215 12460);
FORCEPROP 2 LASTPIN (1225 12400) $PN 24
J 2
(1215 12410);
DISPLAY 0.680851 (1215 12410);
PAINT MONO (1215 12410);
FORCEPROP 2 LASTPIN (1225 12350) $PN 25
J 2
(1215 12360);
DISPLAY 0.680851 (1215 12360);
PAINT MONO (1215 12360);
FORCEPROP 2 LASTPIN (1225 12300) $PN 26
J 2
(1215 12310);
DISPLAY 0.680851 (1215 12310);
PAINT MONO (1215 12310);
FORCEPROP 2 LASTPIN (2025 12000) $PN 13
J 0
(2035 12010);
DISPLAY 0.680851 (2035 12010);
PAINT MONO (2035 12010);
FORCEPROP 2 LASTPIN (2025 12050) $PN 14
J 0
(2035 12060);
DISPLAY 0.680851 (2035 12060);
PAINT MONO (2035 12060);
FORCEPROP 2 LASTPIN (2025 12100) $PN 15
J 0
(2035 12110);
DISPLAY 0.680851 (2035 12110);
PAINT MONO (2035 12110);
FORCEPROP 2 LASTPIN (2025 12150) $PN 16
J 0
(2035 12160);
DISPLAY 0.680851 (2035 12160);
PAINT MONO (2035 12160);
FORCEPROP 2 LASTPIN (2025 12200) $PN 17
J 0
(2035 12210);
DISPLAY 0.680851 (2035 12210);
PAINT MONO (2035 12210);
FORCEPROP 2 LASTPIN (2025 12250) $PN 18
J 0
(2035 12260);
DISPLAY 0.680851 (2035 12260);
PAINT MONO (2035 12260);
FORCEPROP 2 LASTPIN (2025 12300) $PN 19
J 0
(2035 12310);
DISPLAY 0.680851 (2035 12310);
PAINT MONO (2035 12310);
FORCEPROP 2 LASTPIN (2025 12350) $PN 20
J 0
(2035 12360);
DISPLAY 0.680851 (2035 12360);
PAINT MONO (2035 12360);
FORCEPROP 2 LAST PART_TYPE SMLF
J 0
(1397 12739);
DISPLAY 0.680851 (1397 12739);
FORCEPROP 2 LAST VALUE RS31312R
J 0
(1397 12689);
DISPLAY 0.680851 (1397 12689);
FORCEPROP 1 LAST MATERIAL IC
J 0
(1378 12562);
DISPLAY 0.723404 (1378 12562);
PAINT GREEN (1378 12562);
FORCEPROP 0 LAST ROOM SCM_P12V_MPS_BOM2
J 0
(1400 12825);
DISPLAY 0.680851 (1400 12825);
PAINT RED (1400 12825);
FORCEPROP 2 LAST CDS_LIB pure_quanta
J 0
(1625 12025);
DISPLAY INVISIBLE (1625 12025);
FORCEPROP 1 LAST NEEDS_NO_SIZE TRUE
J 0
(1625 12025);
DISPLAY 0.723404 (1625 12025);
PAINT GREEN (1625 12025);
DISPLAY INVISIBLE (1625 12025);
FORCEPROP 1 LAST CDS_LMAN_SYM_OUTLINE -250,525,250,-525
J 0
(1625 12025);
DISPLAY 0.468085 (1625 12025);
PAINT GREEN (1625 12025);
DISPLAY INVISIBLE (1625 12025);
FORCEPROP 2 LAST SEC_TYPE 
J 0
(1400 12975);
DISPLAY 0.680851 (1400 12975);
DISPLAY INVISIBLE (1400 12975);
FORCEPROP 1 LAST PATH I95
J 0
(1625 12025);
DISPLAY 0.723404 (1625 12025);
PAINT GREEN (1625 12025);
DISPLAY INVISIBLE (1625 12025);
FORCEPROP 1 LAST PART_NUMBER AL031312000
J 0
(1375 12600);
DISPLAY 0.723404 (1375 12600);
PAINT GREEN (1375 12600);
DISPLAY INVISIBLE (1375 12600);
FORCEADD DNS..2
(3100 15225);
PAINT RED (3100 15225);
FORCEPROP 2 LAST CDS_LIB mstr_misc
J 0
(3100 15225);
DISPLAY INVISIBLE (3100 15225);
FORCEPROP 1 LAST COMMENT_BODY TRUE
R 1
J 0
(3175 15000);
DISPLAY 0.872340 (3175 15000);
PAINT GREEN (3175 15000);
DISPLAY INVISIBLE (3175 15000);
FORCEADD DNS..2
(3250 12125);
PAINT RED (3250 12125);
FORCEPROP 2 LAST CDS_LIB mstr_misc
J 0
(3250 12125);
DISPLAY INVISIBLE (3250 12125);
FORCEPROP 1 LAST COMMENT_BODY TRUE
R 1
J 0
(3325 11900);
DISPLAY 0.872340 (3325 11900);
PAINT GREEN (3325 11900);
DISPLAY INVISIBLE (3325 11900);
FORCEADD QUANTA_TITLE_BLOCK_C..1
(5275 10325);
FORCEPROP 0 LAST CDS_CON_LAST_MODIFIED Thu Sep 14 16:12:28 2023
J 0
(3390 10340);
DISPLAY INVISIBLE (3390 10340);
FORCEPROP 1 LAST CUSTOM_TXT_CDS <CON_LAST_MODIFIED>
J 0
(3390 10340);
DISPLAY 0.978723 (3390 10340);
FORCEPROP 2 LAST CUSTOM_TXT_CDS <XR_PAGE_TITLE>
J 0
(-2615 15575);
DISPLAY 0.638298 (-2615 15575);
PAINT PINK (-2615 15575);
DISPLAY INVISIBLE (-2615 15575);
FORCEPROP 1 LAST CUSTOM_TXT_CDS <NAME_2>
J 0
(2100 10375);
FORCEPROP 1 LAST CUSTOM_TXT_CDS <NAME_1>
J 0
(2100 10500);
FORCEPROP 1 LAST CUSTOM_TXT_CDS <Q_NUMBER>
J 0
(3872 10428);
DISPLAY 1.212766 (3872 10428);
FORCEPROP 1 LAST CUSTOM_TXT_CDS <Q_PROJ>
J 0
(2893 10427);
DISPLAY 1.212766 (2893 10427);
FORCEPROP 1 LAST CUSTOM_TXT_CDS <Q_REV>
J 0
(5091 10428);
DISPLAY 1.212766 (5091 10428);
FORCEPROP 1 LAST CUSTOM_TXT_CDS <CON_PAGE_NUM> OF <CON_TOTAL_PAGES>
J 0
(4829 10343);
DISPLAY 0.978723 (4829 10343);
FORCEPROP 1 LAST Q_TITLE P12V_SCM
J 0
(-4025 10375);
DISPLAY 2.446809 (-4025 10375);
PAINT GREEN (-4025 10375);
FORCEPROP 2 LAST CDS_LIB pure_quanta
J 0
(5275 10325);
DISPLAY INVISIBLE (5275 10325);
FORCEPROP 1 LAST CDS_LMAN_SYM_OUTLINE -9475,6775,100,-125
J 0
(5275 10325);
DISPLAY 0.468085 (5275 10325);
PAINT GREEN (5275 10325);
DISPLAY INVISIBLE (5275 10325);
FORCEPROP 2 LAST PAGE_BORDER TRUE
J 0
(-2615 15575);
DISPLAY 0.638298 (-2615 15575);
PAINT PINK (-2615 15575);
DISPLAY INVISIBLE (-2615 15575);
FORCEPROP 2 LAST CDS_XR_PAGE_TITLE CR-152 : @T6G_MB_LIB.T6G(SCH_1):PAGE152
J 0
(-2615 15575);
DISPLAY 0.638298 (-2615 15575);
PAINT PINK (-2615 15575);
DISPLAY INVISIBLE (-2615 15575);
FORCEPROP 1 LAST Q_DEPT BU9
J 1
(1512 10374);
DISPLAY 1.957447 (1512 10374);
PAINT GREEN (1512 10374);
DISPLAY INVISIBLE (1512 10374);
FORCEPROP 1 LAST COMMENT_BODY TRUE
J 0
(5287 10312);
DISPLAY 0.978723 (5287 10312);
PAINT GREEN (5287 10312);
DISPLAY INVISIBLE (5287 10312);
FORCEADD DNS..2
(2650 12125);
PAINT RED (2650 12125);
FORCEPROP 2 LAST CDS_LIB mstr_misc
J 0
(2650 12125);
DISPLAY INVISIBLE (2650 12125);
FORCEPROP 1 LAST COMMENT_BODY TRUE
R 1
J 0
(2725 11900);
DISPLAY 0.872340 (2725 11900);
PAINT GREEN (2725 11900);
DISPLAY INVISIBLE (2725 11900);
WIRE 16 -1 (-750 12900)(-750 12975);
WIRE 16 -1 (-2750 13500)(-2750 13575);
WIRE 16 -1 (-2525 14650)(-2525 14750);
WIRE 16 -1 (-1125 14125)(-1125 14025);
WIRE 16 -1 (-450 14475)(-450 14400);
WIRE 16 -1 (-1125 15125)(-1125 15025);
WIRE 16 -1 (825 11300)(825 11375);
WIRE 16 -1 (750 12375)(750 12450);
WIRE 16 -1 (-525 11400)(-525 11550);
WIRE 16 -1 (2875 12900)(2875 12875);
WIRE 16 -1 (3250 11650)(3475 11650);
WIRE 16 -1 (3475 11650)(3475 11675);
WIRE 16 -1 (-75 11325)(-75 11475);
WIRE 16 -1 (4500 12250)(4500 12375);
WIRE 16 -1 (675 14275)(675 14200);
WIRE 16 -1 (1000 15100)(1000 14900);
WIRE 16 -1 (1000 14900)(1125 14900);
WIRE 16 -1 (1000 14900)(1000 14875);
WIRE 16 -1 (350 11150)(350 11075);
WIRE 16 -1 (3775 15000)(4050 15000);
WIRE 16 -1 (200 12150)(-175 12150);
WIRE 16 -1 (-175 13875)(-175 12150);
WIRE 16 -1 (-175 13875)(-750 13875);
WIRE 16 -1 (-750 13375)(-750 13875);
WIRE 16 -1 (-2475 13875)(-750 13875);
WIRE 16 -1 (-2475 14275)(-2475 13875);
WIRE 16 -1 (-2125 14275)(-2475 14275);
WIRE 16 -1 (-2475 14275)(-2525 14275);
WIRE 16 -1 (-2525 14450)(-2525 14275);
WIRE 16 -1 (-2725 14275)(-2525 14275);
FORCEPROP 2 LAST SIG_NAME P12V_SCM_EN
J 0
(-2510 14285);
DISPLAY 0.574468 (-2510 14285);
FORCEPROP 2 LASTPROP $XRERR UNIQUE?
J 0
(-2750 14285);
DISPLAY 0.638298 (-2750 14285);
PAINT MONO (-2750 14285);
DISPLAY INVISIBLE (-2750 14285);
WIRE 16 2175 (-3975 16600)(-2272 16600);
WIRE 16 2175 (-3975 16600)(-3975 15700);
WIRE 16 2175 (-2272 16600)(-2272 15700);
WIRE 16 2175 (-3975 15700)(-2272 15700);
WIRE 16 -1 (2025 12000)(2332 12000);
WIRE 16 -1 (2332 12050)(2332 12000);
WIRE 16 -1 (2332 12050)(2332 12100);
WIRE 16 -1 (2025 12050)(2332 12050);
WIRE 16 -1 (2332 12100)(2332 12150);
WIRE 16 -1 (2025 12100)(2332 12100);
WIRE 16 -1 (2332 12150)(2332 12200);
WIRE 16 -1 (2332 12150)(2025 12150);
WIRE 16 -1 (2332 12200)(2332 12250);
WIRE 16 -1 (2025 12200)(2332 12200);
WIRE 16 -1 (2332 12250)(2332 12300);
WIRE 16 -1 (2025 12250)(2332 12250);
WIRE 16 -1 (2332 12300)(2332 12350);
WIRE 16 -1 (2025 12300)(2332 12300);
WIRE 16 -1 (2332 12350)(2625 12350);
WIRE 16 -1 (2025 12350)(2332 12350);
WIRE 16 -1 (2625 12350)(3225 12350);
WIRE 16 -1 (2625 12225)(2625 12350);
WIRE 16 -1 (3950 12350)(3225 12350);
WIRE 16 -1 (3225 12350)(3225 12225);
WIRE 16 -1 (3950 12350)(3950 12650);
WIRE 16 -1 (3950 12650)(4500 12650);
WIRE 16 -1 (4500 12650)(4500 12700);
WIRE 16 -1 (4500 12575)(4500 12650);
WIRE 16 -1 (1225 12300)(1145 12300);
WIRE 16 -1 (1145 12300)(1145 12350);
WIRE 16 -1 (1225 12350)(1145 12350);
WIRE 16 -1 (1145 12350)(1145 12400);
WIRE 16 -1 (1225 12400)(1145 12400);
WIRE 16 -1 (1145 12400)(1145 12450);
WIRE 16 -1 (1225 12450)(1145 12450);
WIRE 16 -1 (1145 12450)(1145 12500);
WIRE 16 -1 (1145 12750)(1145 12500);
WIRE 16 -1 (1145 12500)(1225 12500);
WIRE 16 -1 (1145 12750)(750 12750);
WIRE 16 -1 (750 12850)(750 12750);
WIRE 16 -1 (750 12750)(750 12650);
WIRE 16 -1 (2625 11900)(2775 11900);
WIRE 16 -1 (2625 12025)(2625 11900);
WIRE 16 -1 (2025 11900)(2625 11900);
FORCEPROP 2 LAST SIG_NAME P12V_SCM_AVIN_PD
J 0
(2115 11910);
DISPLAY 0.574468 (2115 11910);
WIRE 16 -1 (3625 11950)(3625 11800);
WIRE 16 -1 (3625 11800)(3625 11725);
WIRE 16 -1 (3625 11800)(3225 11800);
WIRE 16 -1 (3225 12025)(3225 11800);
WIRE 16 -1 (2025 11800)(3225 11800);
FORCEPROP 2 LAST SIG_NAME P12V_SCM_OV_FB
J 0
(2115 11810);
DISPLAY 0.574468 (2115 11810);
FORCEPROP 2 LASTPROP $XRERR UNIQUE?
J 0
(1875 11810);
DISPLAY 0.638298 (1875 11810);
PAINT MONO (1875 11810);
DISPLAY INVISIBLE (1875 11810);
WIRE 16 -1 (2875 12675)(2875 12500);
WIRE 16 -1 (2875 12500)(3075 12500);
WIRE 16 -1 (2025 12500)(2875 12500);
FORCEPROP 2 LAST SIG_NAME HP_LVC3_SCM_HSC_PWRGD_R
J 0
(2140 12510);
DISPLAY 0.638298 (2140 12510);
FORCEPROP 2 LASTPROP $XRERR UNIQUE?
J 0
(1900 12510);
DISPLAY 0.638298 (1900 12510);
PAINT MONO (1900 12510);
DISPLAY INVISIBLE (1900 12510);
WIRE 16 -1 (2975 11100)(3350 11100);
WIRE 16 -1 (2975 11650)(2975 11100);
WIRE 16 -1 (3050 11650)(2975 11650);
WIRE 16 -1 (2975 11650)(2025 11650);
FORCEPROP 2 LAST SIG_NAME P12V_SCM_FLTB_N
J 0
(2115 11660);
DISPLAY 0.574468 (2115 11660);
FORCEPROP 2 LASTPROP $XRERR UNIQUE?
J 0
(1875 11660);
DISPLAY 0.638298 (1875 11660);
PAINT MONO (1875 11660);
DISPLAY INVISIBLE (1875 11660);
WIRE 16 -1 (2600 11400)(2600 11550);
WIRE 16 -1 (2250 11550)(2600 11550);
WIRE 16 -1 (2250 11375)(2250 11550);
FORCEPROP 2 LAST SIG_NAME P12V_SCM_IMON
J 0
(2115 11560);
DISPLAY 0.574468 (2115 11560);
FORCEPROP 2 LASTPROP $XRERR UNIQUE?
J 0
(1875 11560);
DISPLAY 0.638298 (1875 11560);
PAINT MONO (1875 11560);
DISPLAY INVISIBLE (1875 11560);
WIRE 16 -1 (2025 11550)(2250 11550);
WIRE 16 -1 (400 12150)(1225 12150);
FORCEPROP 2 LAST SIG_NAME P12V_SCM_EN_R2
J 0
(715 12160);
DISPLAY 0.574468 (715 12160);
FORCEPROP 2 LASTPROP $XRERR UNIQUE?
J 0
(475 12160);
DISPLAY 0.638298 (475 12160);
PAINT MONO (475 12160);
DISPLAY INVISIBLE (475 12160);
WIRE 16 -1 (1225 12050)(900 12050);
WIRE 16 -1 (900 12050)(900 11950);
WIRE 16 -1 (900 11950)(1225 11950);
WIRE 16 -1 (900 11950)(425 11950);
WIRE 16 -1 (-525 11850)(1225 11850);
FORCEPROP 2 LAST SIG_NAME P12V_SCM_TIMER
J 0
(715 11860);
DISPLAY 0.574468 (715 11860);
FORCEPROP 2 LASTPROP $XRERR UNIQUE?
J 0
(475 11860);
DISPLAY 0.638298 (475 11860);
PAINT MONO (475 11860);
DISPLAY INVISIBLE (475 11860);
WIRE 16 -1 (-525 11850)(-525 11750);
WIRE 16 -1 (1225 11750)(350 11750);
FORCEPROP 2 LAST SIG_NAME P12V_SCM_ISET
J 0
(740 11760);
DISPLAY 0.574468 (740 11760);
FORCEPROP 2 LASTPROP $XRERR UNIQUE?
J 0
(500 11760);
DISPLAY 0.638298 (500 11760);
PAINT MONO (500 11760);
DISPLAY INVISIBLE (500 11760);
WIRE 16 -1 (350 11750)(350 11650);
WIRE 16 -1 (350 11750)(-75 11750);
WIRE 16 -1 (-75 11750)(-75 11675);
WIRE 16 -1 (1225 11650)(825 11650);
FORCEPROP 2 LAST SIG_NAME P12V_SCM_SS
J 0
(790 11660);
DISPLAY 0.574468 (790 11660);
FORCEPROP 2 LASTPROP $XRERR UNIQUE?
J 0
(550 11660);
DISPLAY 0.638298 (550 11660);
PAINT MONO (550 11660);
DISPLAY INVISIBLE (550 11660);
WIRE 16 -1 (825 11650)(825 11575);
WIRE 16 -1 (1166 11550)(1225 11550);
WIRE 16 -1 (1166 11466)(1166 11550);
WIRE 16 3135 (1900 13850)(3150 13850);
WIRE 16 3135 (1900 13200)(1900 13850);
WIRE 16 3135 (3150 13200)(3150 13850);
WIRE 16 3135 (1900 13200)(3150 13200);
WIRE 16 3135 (1925 13300)(3125 13300);
WIRE 16 3135 (1925 13400)(3125 13400);
WIRE 16 3135 (1925 13500)(3125 13500);
WIRE 16 -1 (1850 14500)(1850 14250);
WIRE 16 -1 (1875 14500)(1850 14500);
WIRE 16 -1 (1850 14250)(1525 14250);
WIRE 16 -1 (1525 14250)(1525 14275);
WIRE 16 -1 (1525 14200)(1525 14250);
WIRE 16 -1 (675 14550)(675 14500);
WIRE 16 -1 (675 14500)(975 14500);
WIRE 16 -1 (675 14500)(675 14475);
WIRE 16 -1 (975 14500)(975 14700);
WIRE 16 -1 (975 14700)(1875 14700);
FORCEPROP 2 LAST SIG_NAME P12V_SCM_OV
J 0
(1465 14710);
DISPLAY 0.574468 (1465 14710);
FORCEPROP 2 LASTPROP $XRERR UNIQUE?
J 0
(1225 14710);
DISPLAY 0.638298 (1225 14710);
PAINT MONO (1225 14710);
DISPLAY INVISIBLE (1225 14710);
WIRE 16 3135 (1925 13600)(3125 13600);
WIRE 16 -1 (4150 11375)(4150 11525);
WIRE 16 -1 (3825 11375)(4150 11375);
WIRE 16 -1 (3625 11375)(3825 11375);
WIRE 16 -1 (3825 11375)(3825 11350);
WIRE 16 -1 (3625 11525)(3625 11375);
WIRE 16 -1 (3625 12150)(3625 12250);
WIRE 16 -1 (3625 12250)(4150 12250);
WIRE 16 -1 (4150 12300)(4150 12250);
WIRE 16 -1 (4150 12250)(4150 12150);
WIRE 16 -1 (4750 11775)(4150 11775);
FORCEPROP 2 LAST SIG_NAME P12V_SCM_AVIN_PD
J 0
(4265 11785);
DISPLAY 0.574468 (4265 11785);
WIRE 16 -1 (4150 11950)(4150 11775);
WIRE 16 -1 (4150 11775)(4150 11725);
WIRE 16 -1 (4800 15925)(4800 16025);
WIRE 16 -1 (4800 16075)(4800 16025);
WIRE 16 -1 (4800 16025)(4400 16025);
WIRE 16 -1 (4400 16025)(4400 15925);
WIRE 16 -1 (4400 16025)(3975 16025);
WIRE 16 -1 (3975 15925)(3975 16025);
WIRE 16 -1 (3975 16025)(3500 16025);
WIRE 16 -1 (3500 16025)(3500 15975);
WIRE 16 -1 (3295 16025)(3500 16025);
WIRE 16 -1 (3295 16025)(3295 15400);
WIRE 16 -1 (3295 15400)(3400 15400);
WIRE 16 -1 (3295 15400)(3075 15400);
WIRE 16 -1 (3075 15325)(3075 15400);
WIRE 16 -1 (2982 15400)(3075 15400);
WIRE 16 -1 (3400 15400)(3400 15350);
WIRE 16 -1 (2675 15400)(2982 15400);
WIRE 16 -1 (2982 15350)(2982 15400);
WIRE 16 -1 (2982 15300)(2982 15350);
WIRE 16 -1 (2675 15350)(2982 15350);
WIRE 16 -1 (2982 15250)(2982 15300);
WIRE 16 -1 (2675 15300)(2982 15300);
WIRE 16 -1 (2982 15200)(2982 15250);
WIRE 16 -1 (2675 15250)(2982 15250);
WIRE 16 -1 (2982 15150)(2982 15200);
WIRE 16 -1 (2982 15200)(2675 15200);
WIRE 16 -1 (2982 15100)(2982 15150);
WIRE 16 -1 (2675 15150)(2982 15150);
WIRE 16 -1 (2675 15100)(2982 15100);
WIRE 16 -1 (4800 15650)(4800 15725);
WIRE 16 -1 (4800 15575)(4800 15650);
WIRE 16 -1 (4800 15650)(4400 15650);
WIRE 16 -1 (4400 15650)(4400 15725);
WIRE 16 -1 (4400 15650)(3975 15650);
WIRE 16 -1 (3975 15650)(3975 15725);
WIRE 16 -1 (3500 15650)(3975 15650);
WIRE 16 -1 (3500 15725)(3500 15650);
WIRE 16 -1 (4525 15400)(4300 15400);
WIRE 16 -1 (4525 15400)(4525 15250);
WIRE 16 -1 (4300 15450)(4300 15400);
WIRE 16 -1 (4300 15400)(4100 15400);
WIRE 16 -1 (4100 15400)(4100 15250);
WIRE 16 -1 (3125 14425)(3125 14300);
WIRE 16 -1 (3000 14300)(3125 14300);
WIRE 16 -1 (3000 14200)(3000 14300);
WIRE 16 -1 (2900 14300)(3000 14300);
WIRE 16 -1 (2900 14600)(2900 14300);
WIRE 16 -1 (2900 14300)(2850 14300);
WIRE 16 -1 (2850 14500)(2850 14300);
WIRE 16 -1 (2800 14300)(2850 14300);
WIRE 16 -1 (2675 14600)(2900 14600);
WIRE 16 -1 (2800 14450)(2800 14300);
WIRE 16 -1 (2750 14300)(2800 14300);
WIRE 16 -1 (2675 14500)(2850 14500);
WIRE 16 -1 (2750 14300)(2750 14400);
WIRE 16 -1 (2675 14450)(2800 14450);
WIRE 16 -1 (2750 14400)(2675 14400);
WIRE 16 -1 (2250 11175)(2250 10995);
WIRE 16 -1 (2250 10995)(2600 10995);
WIRE 16 -1 (2600 10995)(2600 11200);
WIRE 16 -1 (2600 10995)(2600 10925);
WIRE 16 -1 (-50 15800)(-50 15850);
WIRE 16 -1 (-50 15850)(100 15850);
WIRE 16 -1 (100 15925)(100 15850);
WIRE 16 -1 (325 15850)(100 15850);
WIRE 16 -1 (325 15850)(675 15850);
WIRE 16 -1 (325 15850)(325 15725);
WIRE 16 -1 (675 15850)(1000 15850);
WIRE 16 -1 (675 15850)(675 15425);
WIRE 16 -1 (1775 15850)(1000 15850);
WIRE 16 -1 (1000 15850)(1000 15725);
WIRE 16 -1 (1775 15850)(1775 15400);
WIRE 16 -1 (1775 15400)(1875 15400);
WIRE 16 -1 (1775 15400)(1775 15350);
WIRE 16 -1 (1775 15350)(1875 15350);
WIRE 16 -1 (1775 15350)(1775 15300);
WIRE 16 -1 (1775 15300)(1875 15300);
WIRE 16 -1 (1775 15300)(1775 15250);
WIRE 16 -1 (1775 15250)(1875 15250);
WIRE 16 -1 (1775 15250)(1775 15200);
WIRE 16 -1 (1775 15200)(1875 15200);
WIRE 16 -1 (1775 15200)(1775 15150);
WIRE 16 -1 (1775 15150)(1875 15150);
WIRE 16 -1 (1775 15150)(1775 15100);
WIRE 16 -1 (1775 15100)(1875 15100);
WIRE 16 -1 (325 15360)(325 15525);
WIRE 16 -1 (325 15360)(100 15360);
WIRE 16 -1 (100 15300)(100 15360);
WIRE 16 -1 (-50 15360)(100 15360);
WIRE 16 -1 (-50 15500)(-50 15360);
WIRE 16 -1 (3425 12900)(4100 12900);
FORCEPROP 2 LAST SIG_NAME HP_LVC3_SCM_HSC_PWRGD
J 0
(3565 12935);
DISPLAY 0.553191 (3565 12935);
WIRE 16 -1 (3425 12900)(3425 12500);
WIRE 16 -1 (3425 12500)(3275 12500);
WIRE 16 3135 (2700 13825)(2700 13225);
WIRE 16 -1 (4525 15050)(4525 14900);
FORCEPROP 2 LAST SIG_NAME HP_LVC3_SCM_HSC_PWRGD
J 0
(4290 14910);
DISPLAY 0.574468 (4290 14910);
WIRE 16 -1 (4525 14900)(4950 14900);
WIRE 16 -1 (3850 14900)(4525 14900);
WIRE 16 -1 (350 11450)(350 11350);
FORCEPROP 2 LAST SIG_NAME P12V_SCM_ISET_R
J 0
(365 11385);
DISPLAY 0.468085 (365 11385);
FORCEPROP 2 LASTPROP $XRERR UNIQUE?
J 0
(125 11385);
DISPLAY 0.638298 (125 11385);
PAINT MONO (125 11385);
DISPLAY INVISIBLE (125 11385);
WIRE 16 3135 (2275 13825)(2275 13225);
WIRE 16 -1 (-1700 13175)(-950 13175);
FORCEPROP 2 LAST SIG_NAME FM_SCM_PRSNT1_R_N
J 0
(-1535 13185);
DISPLAY 0.638298 (-1535 13185);
PAINT WHITE (-1535 13185);
FORCEPROP 2 LASTPROP $XRERR UNIQUE?
J 0
(-1775 13185);
DISPLAY 0.638298 (-1775 13185);
PAINT MONO (-1775 13185);
DISPLAY INVISIBLE (-1775 13185);
WIRE 16 -1 (-1925 14275)(-1375 14275);
FORCEPROP 2 LAST SIG_NAME P12V_SCM_EN_R
J 0
(-1760 14285);
DISPLAY 0.595745 (-1760 14285);
FORCEPROP 2 LASTPROP $XRERR UNIQUE?
J 0
(-2000 14285);
DISPLAY 0.638298 (-2000 14285);
PAINT MONO (-2000 14285);
DISPLAY INVISIBLE (-2000 14285);
WIRE 16 -1 (-1125 14525)(-1125 14625);
WIRE 16 -1 (-1125 14625)(-700 14625);
FORCEPROP 2 LAST SIG_NAME P12V_SCM_EN_G
J 0
(-1085 14635);
DISPLAY 0.595745 (-1085 14635);
FORCEPROP 2 LASTPROP $XRERR UNIQUE?
J 0
(-1325 14635);
DISPLAY 0.638298 (-1325 14635);
PAINT MONO (-1325 14635);
DISPLAY INVISIBLE (-1325 14635);
WIRE 16 -1 (-1125 14825)(-1125 14625);
WIRE 16 -1 (675 14800)(1875 14800);
FORCEPROP 2 LAST SIG_NAME P12V_SCM_UV
J 0
(1465 14810);
DISPLAY 0.574468 (1465 14810);
FORCEPROP 2 LASTPROP $XRERR UNIQUE?
J 0
(1225 14810);
DISPLAY 0.638298 (1225 14810);
PAINT MONO (1225 14810);
DISPLAY INVISIBLE (1225 14810);
WIRE 16 -1 (675 14800)(675 15000);
WIRE 16 -1 (675 14800)(675 14750);
WIRE 16 -1 (675 15225)(675 15000);
WIRE 16 -1 (200 15000)(675 15000);
WIRE 16 -1 (1325 14900)(1875 14900);
FORCEPROP 2 LAST SIG_NAME P12V_SCM_REG
J 0
(1440 14910);
DISPLAY 0.574468 (1440 14910);
FORCEPROP 2 LASTPROP $XRERR UNIQUE?
J 0
(1200 14910);
DISPLAY 0.638298 (1200 14910);
PAINT MONO (1200 14910);
DISPLAY INVISIBLE (1200 14910);
WIRE 16 -1 (2675 14900)(3650 14900);
FORCEPROP 2 LAST SIG_NAME P12V_SCM_PWRGD
J 0
(2765 14910);
DISPLAY 0.574468 (2765 14910);
FORCEPROP 2 LASTPROP $XRERR UNIQUE?
J 0
(2525 14910);
DISPLAY 0.638298 (2525 14910);
PAINT MONO (2525 14910);
DISPLAY INVISIBLE (2525 14910);
WIRE 16 -1 (2675 15000)(3075 15000);
FORCEPROP 2 LAST SIG_NAME P12V_SCM_GATE
J 0
(2765 15010);
DISPLAY 0.574468 (2765 15010);
FORCEPROP 2 LASTPROP $XRERR UNIQUE?
J 0
(2525 15010);
DISPLAY 0.638298 (2525 15010);
PAINT MONO (2525 15010);
DISPLAY INVISIBLE (2525 15010);
WIRE 16 -1 (3400 15000)(3075 15000);
WIRE 16 -1 (3075 15125)(3075 15000);
WIRE 16 -1 (3400 15150)(3400 15000);
WIRE 16 -1 (3575 15000)(3400 15000);
WIRE 16 -1 (2675 14800)(3650 14800);
FORCEPROP 2 LAST SIG_NAME P12V_SCM_FAULT_N
J 0
(2765 14810);
DISPLAY 0.574468 (2765 14810);
FORCEPROP 2 LASTPROP $XRERR UNIQUE?
J 0
(2525 14810);
DISPLAY 0.638298 (2525 14810);
PAINT MONO (2525 14810);
DISPLAY INVISIBLE (2525 14810);
WIRE 16 -1 (0 15000)(-450 15000);
FORCEPROP 2 LAST SIG_NAME P12V_SCM_UV_R
J 0
(-385 15010);
DISPLAY 0.574468 (-385 15010);
FORCEPROP 2 LASTPROP $XRERR UNIQUE?
J 0
(-625 15010);
DISPLAY 0.638298 (-625 15010);
PAINT MONO (-625 15010);
DISPLAY INVISIBLE (-625 15010);
WIRE 16 -1 (-450 14875)(-450 15000);
WIRE 16 -1 (1350 15425)(1350 15000);
WIRE 16 -1 (1350 15425)(1000 15425);
WIRE 16 -1 (1350 15000)(1875 15000);
FORCEPROP 2 LAST SIG_NAME P12V_SCM_VCC
J 0
(1440 15010);
DISPLAY 0.574468 (1440 15010);
FORCEPROP 2 LASTPROP $XRERR UNIQUE?
J 0
(1200 15010);
DISPLAY 0.638298 (1200 15010);
PAINT MONO (1200 15010);
DISPLAY INVISIBLE (1200 15010);
WIRE 16 -1 (1000 15525)(1000 15425);
WIRE 16 -1 (1000 15425)(1000 15300);
WIRE 16 -1 (1875 14600)(1525 14600);
FORCEPROP 2 LAST SIG_NAME P12V_SCM_CB
J 0
(1465 14610);
DISPLAY 0.574468 (1465 14610);
FORCEPROP 2 LASTPROP $XRERR UNIQUE?
J 0
(1225 14610);
DISPLAY 0.638298 (1225 14610);
PAINT MONO (1225 14610);
DISPLAY INVISIBLE (1225 14610);
WIRE 16 -1 (1525 14600)(1525 14475);
WIRE 16 -1 (3850 14800)(4100 14800);
WIRE 16 -1 (4100 14800)(4950 14800);
FORCEPROP 2 LAST SIG_NAME P12V_SCM_FAULT_R_N
J 0
(4215 14810);
DISPLAY 0.680851 (4215 14810);
WIRE 16 -1 (4100 15050)(4100 14800);
WIRE 16 -1 (3125 14625)(3125 14700);
FORCEPROP 2 LAST SIG_NAME P12V_SCM_SENSE
J 0
(2765 14710);
DISPLAY 0.574468 (2765 14710);
FORCEPROP 2 LASTPROP $XRERR UNIQUE?
J 0
(2525 14710);
DISPLAY 0.638298 (2525 14710);
PAINT MONO (2525 14710);
DISPLAY INVISIBLE (2525 14710);
WIRE 16 -1 (2675 14700)(3125 14700);
WIRE 16 3135 (1925 13700)(3125 13700);
WIRE 16 -1 (-2925 14275)(-3700 14275);
FORCEPROP 2 LAST SIG_NAME VIRTUAL_RESEAT_FPGA_N
J 0
(-3710 14285);
DISPLAY 0.808511 (-3710 14285);
WIRE 16 -1 (3550 11100)(4475 11100);
FORCEPROP 2 LAST SIG_NAME P12V_SCM_FAULT_R_N
J 0
(3765 11110);
DISPLAY 0.680851 (3765 11110);
WIRE 16 -1 (-2975 13175)(-2750 13175);
WIRE 16 -1 (-2750 13175)(-1900 13175);
FORCEPROP 2 LAST SIG_NAME FM_SCM_PRSNT1_N
J 0
(-2635 13185);
DISPLAY 0.638298 (-2635 13185);
PAINT WHITE (-2635 13185);
WIRE 16 -1 (-2750 13300)(-2750 13175);
DOT 1 (2250 11550);
DOT 1 (2600 10995);
DOT 1 (2982 15300);
DOT 1 (2625 11900);
DOT 1 (2332 12100);
DOT 1 (2332 12250);
DOT 1 (1145 12400);
DOT 1 (1145 12500);
DOT 1 (3825 11375);
DOT 1 (4800 16025);
DOT 1 (4800 15650);
DOT 1 (4400 15650);
DOT 1 (3975 16025);
DOT 1 (3500 16025);
DOT 1 (2982 15350);
DOT 1 (3000 14300);
DOT 1 (2900 14300);
DOT 1 (2850 14300);
DOT 1 (2800 14300);
DOT 1 (1000 15850);
DOT 1 (675 15850);
DOT 1 (1775 15300);
DOT 1 (4500 12650);
DOT 1 (4150 12250);
DOT 1 (2332 12350);
DOT 1 (325 15850);
DOT 1 (100 15850);
DOT 1 (100 15360);
DOT 1 (-750 13875);
DOT 1 (-2525 14275);
DOT 1 (-2750 13175);
DOT 1 (2625 12350);
DOT 1 (4100 14800);
DOT 1 (4400 16025);
DOT 1 (1775 15400);
DOT 1 (1775 15350);
DOT 1 (2982 15200);
DOT 1 (2982 15150);
DOT 1 (3075 15400);
DOT 1 (3975 15650);
DOT 1 (2982 15400);
DOT 1 (4525 14900);
DOT 1 (3400 15000);
DOT 1 (2982 15250);
DOT 1 (3295 15400);
DOT 1 (4300 15400);
DOT 1 (1525 14250);
DOT 1 (1000 15425);
DOT 1 (675 15000);
DOT 1 (1000 14900);
DOT 1 (1775 15150);
DOT 1 (1775 15250);
DOT 1 (1775 15200);
DOT 1 (3075 15000);
DOT 1 (675 14800);
DOT 1 (-1125 14625);
DOT 1 (-2475 14275);
DOT 1 (750 12750);
DOT 1 (350 11750);
DOT 1 (900 11950);
DOT 1 (1145 12450);
DOT 1 (2332 12200);
DOT 1 (3225 12350);
DOT 1 (2332 12150);
DOT 1 (2332 12300);
DOT 1 (3625 11800);
DOT 1 (2975 11650);
DOT 1 (4150 11775);
DOT 1 (675 14500);
DOT 1 (2875 12500);
DOT 1 (1145 12350);
DOT 1 (2332 12050);
DOT 1 (3225 11800);
FORCENOTE
TDELAY: 6.29MS
(-1050 11100) 0;
DISPLAY LEFT (-1050 11100);
DISPLAY 1.021277 (-1050 11100);
PAINT WHITE (-1050 11100);
FORCENOTE
TFAULT: 1.27MS
(-1050 11175) 0;
DISPLAY LEFT (-1050 11175);
DISPLAY 1.021277 (-1050 11175);
PAINT WHITE (-1050 11175);
FORCENOTE
P12V_SCM_R
(-3925 16425) 0;
DISPLAY LEFT (-3925 16425);
DISPLAY 1.021277 (-3925 16425);
FORCENOTE
OCP=MAX*1.3=5.2A
(-3925 16275) 0;
DISPLAY LEFT (-3925 16275);
DISPLAY 1.021277 (-3925 16275);
FORCENOTE
DESIGN SPECIFICATION
(-3938 16519) 0;
DISPLAY LEFT (-3938 16519);
DISPLAY 1.170213 (-3938 16519);
FORCENOTE
IMAX=4A
(-3925 16350) 0;
DISPLAY LEFT (-3925 16350);
DISPLAY 1.021277 (-3925 16350);
FORCENOTE
MP5025A/
(2750 13775) 0;
DISPLAY LEFT (2750 13775);
DISPLAY 1.021277 (2750 13775);
FORCENOTE
POP
(2800 13625) 0;
DISPLAY LEFT (2800 13625);
DISPLAY 1.021277 (2800 13625);
FORCENOTE
MP5022A
(2750 13725) 0;
DISPLAY LEFT (2750 13725);
DISPLAY 1.021277 (2750 13725);
FORCENOTE
MP5025C/
(2300 13775) 0;
DISPLAY LEFT (2300 13775);
DISPLAY 1.021277 (2300 13775);
FORCENOTE
MP5022C
(2300 13725) 0;
DISPLAY LEFT (2300 13725);
DISPLAY 1.021277 (2300 13725);
FORCENOTE
POP
(2325 13425) 0;
DISPLAY LEFT (2325 13425);
DISPLAY 1.021277 (2325 13425);
FORCENOTE
PR4006
(1975 13625) 0;
DISPLAY LEFT (1975 13625);
DISPLAY 1.021277 (1975 13625);
FORCENOTE
START UP TIME:8.21MS
(4075 14625) 0;
DISPLAY LEFT (4075 14625);
DISPLAY 1.021277 (4075 14625);
PAINT WHITE (4075 14625);
FORCENOTE
ENABLE:
(-1025 11950) 0;
DISPLAY LEFT (-1025 11950);
DISPLAY 1.021277 (-1025 11950);
PAINT WHITE (-1025 11950);
FORCENOTE
OVP: 14.91V
(100 14675) 0;
DISPLAY LEFT (100 14675);
DISPLAY 1.021277 (100 14675);
PAINT WHITE (100 14675);
FORCENOTE
UVP: 10.17V
(100 14750) 0;
DISPLAY LEFT (100 14750);
DISPLAY 1.021277 (100 14750);
PAINT WHITE (100 14750);
FORCENOTE
VIMON(MAX)= 1.610V @ IOUT=5.35A
(900 10775) 0;
DISPLAY LEFT (900 10775);
DISPLAY 1.021277 (900 10775);
PAINT WHITE (900 10775);
FORCENOTE
START UP TIME:8.62MS
(700 10925) 0;
DISPLAY LEFT (700 10925);
DISPLAY 1.021277 (700 10925);
PAINT WHITE (700 10925);
FORCENOTE
DE-POP
(2750 13425) 0;
DISPLAY LEFT (2750 13425);
DISPLAY 1.021277 (2750 13425);
FORCENOTE
POP
(2800 13525) 0;
DISPLAY LEFT (2800 13525);
DISPLAY 1.021277 (2800 13525);
FORCENOTE
PR4009
(1975 13525) 0;
DISPLAY LEFT (1975 13525);
DISPLAY 1.021277 (1975 13525);
FORCENOTE
DE-POP
(2325 13625) 0;
DISPLAY LEFT (2325 13625);
DISPLAY 1.021277 (2325 13625);
FORCENOTE
DE-POP
(2325 13525) 0;
DISPLAY LEFT (2325 13525);
DISPLAY 1.021277 (2325 13525);
FORCENOTE
VIMON(MAX)= 1.563V @ IOUT=5.34A
(3100 14200) 0;
DISPLAY LEFT (3100 14200);
DISPLAY 1.021277 (3100 14200);
PAINT WHITE (3100 14200);
FORCENOTE
DE-POP
(2750 13325) 0;
DISPLAY LEFT (2750 13325);
DISPLAY 1.021277 (2750 13325);
FORCENOTE
DE-POP
(2750 13225) 0;
DISPLAY LEFT (2750 13225);
DISPLAY 1.021277 (2750 13225);
FORCENOTE
VTH>1.391V(HIGH)
(-1025 11884) 0;
DISPLAY LEFT (-1025 11884);
DISPLAY 1.021277 (-1025 11884);
PAINT WHITE (-1025 11884);
FORCENOTE
POP
(2325 13225) 0;
DISPLAY LEFT (2325 13225);
DISPLAY 1.021277 (2325 13225);
FORCENOTE
POP
(2325 13325) 0;
DISPLAY LEFT (2325 13325);
DISPLAY 1.021277 (2325 13325);
FORCENOTE
PU299 OPTIONAL BOM
(1925 13875) 0;
DISPLAY LEFT (1925 13875);
DISPLAY 1.021277 (1925 13875);
FORCENOTE
PR4010
(1975 13425) 0;
DISPLAY LEFT (1975 13425);
DISPLAY 1.021277 (1975 13425);
FORCENOTE
PR4014
(1975 13325) 0;
DISPLAY LEFT (1975 13325);
DISPLAY 1.021277 (1975 13325);
FORCENOTE
PC2239
(1975 13225) 0;
DISPLAY LEFT (1975 13225);
DISPLAY 1.021277 (1975 13225);
FORCENOTE
2ND SOURCE OF PU300
(1100 12975) 0;
DISPLAY LEFT (1100 12975);
DISPLAY 1.276596 (1100 12975);
QUIT
